G04 ================== begin FILE IDENTIFICATION RECORD ==================*
G04 Layout Name:  t6mg_pdb_a_v02_0109_1330.brd*
G04 Film Name:    bot.art*
G04 File Format:  Gerber RS274X*
G04 File Origin:  Cadence Allegro 16.3-S038*
G04 Origin Date:  Mon Jan 13 14:11:50 2014*
G04 *
G04 Layer:  DRAWING FORMAT/TITLE_BLOCK*
G04 Layer:  VIA CLASS/BOTTOM*
G04 Layer:  PIN/BOTTOM*
G04 Layer:  MANUFACTURING/PHOTOPLOT_OUTLINE*
G04 Layer:  ETCH/BOTTOM*
G04 Layer:  DRAWING FORMAT/TITLE_DATA_BOT*
G04 *
G04 Offset:    (0.00 0.00)*
G04 Mirror:    No*
G04 Mode:      Positive*
G04 Rotation:  0*
G04 FullContactRelief:  No*
G04 UndefLineWidth:     6.00*
G04 ================== end FILE IDENTIFICATION RECORD ====================*
%FSLAX25Y25*MOIN*%
%IR0*IPPOS*OFA0.00000B0.00000*MIA0B0*SFA1.00000B1.00000*%
%ADD11C,.02*%
%ADD25C,.03*%
%ADD16C,.04*%
%ADD14C,.052*%
%ADD21C,.026*%
%ADD12C,.063*%
%ADD33C,.046*%
%ADD29C,.064*%
%ADD23C,.055*%
%ADD18R,.04X.04*%
%ADD28C,.039*%
%ADD20C,.093*%
%ADD27R,.052X.052*%
%ADD19C,.077*%
%ADD17C,.095*%
%ADD13R,.063X.063*%
%ADD32R,.046X.046*%
%ADD30R,.064X.064*%
%ADD24R,.055X.055*%
%ADD31C,.099*%
%ADD22R,.077X.077*%
%ADD35O,.205X.244*%
%ADD38R,.02X.018*%
%ADD39R,.018X.02*%
%ADD10C,.132*%
%ADD34C,.205*%
%ADD36C,.315*%
%ADD15C,.126*%
%ADD37R,.014X.059*%
%ADD26C,.158*%
%ADD40C,.014*%
%ADD41C,.018*%
%ADD42C,.005*%
%ADD43C,.006*%
%ADD66C,.03004*%
%ADD68C,.05004*%
%ADD60C,.03604*%
%ADD54C,.07304*%
%ADD67C,.05604*%
%ADD59C,.07404*%
%ADD57C,.06504*%
%ADD56C,.08704*%
%ADD48C,.08409*%
%ADD50C,.12806*%
%ADD46C,.16406*%
%ADD69C,.198*%
%ADD64R,.06502X.06502*%
%ADD53R,.07304X.07302*%
%ADD52C,.13266*%
%ADD63R,.06504X.06502*%
%ADD61R,.07404X.07402*%
%ADD58R,.06502X.06504*%
%ADD55R,.07304X.07304*%
%ADD45C,.28352*%
%ADD65R,.06504X.06504*%
%ADD62R,.07404X.07404*%
%ADD49C,.39376*%
%ADD44O,.28352X.32289*%
%ADD51C,.39377*%
%ADD47C,.39378*%
G75*
%LPD*%
G75*
G36*
G01X104331Y2004D02*
G02X100429Y5906I0J3902D01*
G01Y9843D01*
G03X92520Y17752I-7909J0D01*
G01X5906D01*
G02X2004Y21654I0J3902D01*
G01Y2064961D01*
G02X5905Y2068862I3901J0D01*
G01X92520D01*
G03X100429Y2076772I0J7909D01*
G01Y2080709D01*
G02X104331Y2084610I3902J-1D01*
G01X397638D01*
G02X403508Y2078740I0J-5870D01*
G01Y7874D01*
G02X397638Y2004I-5870J0D01*
G01X104331D01*
G37*
%LPC*%
G75*
G36*
G01X104331Y3997D02*
X104330D01*
G02X102422Y5906I0J1908D01*
G01Y9843D01*
G03X92520Y19745I-9903J-1D01*
G01X91602D01*
Y19746D01*
X5906D01*
Y19745D01*
X5905D01*
G02X3998Y21711I1J1908D01*
G01Y2064961D01*
G02X4556Y2066310I1908J1D01*
G02X5964Y2066868I1349J-1349D01*
G01X92520D01*
G03X99522Y2069769I-1J9903D01*
G03X102422Y2076772I-7003J7002D01*
G01Y2080709D01*
G02X104330Y2082617I1908J0D01*
G01X104331D01*
Y2082616D01*
X397638D01*
G02X401514Y2078740I0J-3876D01*
G01Y1915551D01*
X401515Y1915541D01*
Y1915529D01*
X401514D01*
Y7874D01*
G02X397638Y3998I-3876J0D01*
G01X104331D01*
Y3997D01*
G37*
%LPD*%
G75*
G36*
G01X374483Y675120D02*
X371056Y678548D01*
Y685049D01*
X371285Y685466D01*
X371382Y685533D01*
G03X371516Y685631I-1704J2471D01*
G03X371655Y685746I-1843J2369D01*
G03X371701Y685788I-2000J2237D01*
G03X371798Y685881I-2028J2212D01*
G01X378702Y692785D01*
Y709744D01*
X392818Y723860D01*
Y750004D01*
X397801Y754987D01*
G02X399508Y754280I707J-707D01*
G01Y7874D01*
G02X397638Y6004I-1870J0D01*
G01X104929D01*
G02X104429Y6504I0J500D01*
G01Y9843D01*
G03X92520Y21752I-11909J0D01*
G01X34944D01*
G02X34405Y23594I0J1000D01*
G03X25553I-4426J6906D01*
G02X25014Y21752I-539J-842D01*
G01X6504D01*
G02X6004Y22252I0J500D01*
G01Y494489D01*
X7909Y496394D01*
X37797D01*
X39991Y494200D01*
Y490465D01*
X25238Y475712D01*
Y475164D01*
X25148Y475073D01*
Y448597D01*
X25167Y448577D01*
X25202Y448542D01*
X28013Y445701D01*
X41430Y432287D01*
G02X41576Y431934I-354J-353D01*
G01Y394709D01*
X44866Y391419D01*
Y384909D01*
X45553Y384221D01*
X46233Y383541D01*
Y382935D01*
X50992Y378176D01*
X51598D01*
X51625Y378150D01*
X62732D01*
G03X66085Y377442I2247J2350D01*
G03X67417Y378347I-1105J3058D01*
G03X68004Y381695I-2438J2153D01*
G01X67949Y381834D01*
X68010Y382127D01*
X70232Y384349D01*
Y386681D01*
X70434Y386884D01*
Y397178D01*
X70232Y397381D01*
Y405500D01*
G03X66295Y417631I-5253J4999D01*
G02X65886Y418123I91J492D01*
G01Y432578D01*
X40651Y457813D01*
Y474932D01*
X84272Y518553D01*
Y518636D01*
X85584Y519948D01*
Y556355D01*
X84272Y557667D01*
Y559696D01*
X78424Y565544D01*
Y754438D01*
X79342Y755356D01*
X82924D01*
X92112Y746168D01*
X93414D01*
X93508Y746128D01*
G03X98667Y746438I2268J5341D01*
G01X98722Y746469D01*
X98855Y746506D01*
G02X99342Y746377I133J-482D01*
G01X101159Y744560D01*
X101181Y744391D01*
G03X111237Y741246I5754J748D01*
G02X112891Y740984I741J-671D01*
G03X113814Y739439I7028J3151D01*
G02Y738829I-396J-305D01*
G03Y729439I6106J-4695D01*
G02Y728829I-396J-305D01*
G03Y719439I6106J-4695D01*
G02Y718829I-396J-305D01*
G03X112218Y714137I6106J-4694D01*
G01Y713930D01*
X99904Y701616D01*
X97439D01*
G03X91819Y693913I0J-5902D01*
G01X91862Y693779D01*
X91796Y693507D01*
X90798Y692509D01*
Y435139D01*
X97937Y428002D01*
G02X98084Y427670I-352J-355D01*
G01Y409463D01*
X98382Y409165D01*
X98581Y408965D01*
Y405489D01*
X109196Y394874D01*
Y393594D01*
G02X107685Y392734I-1000J0D01*
G03Y389704I-976J-1515D01*
G02X109196Y388844I511J-860D01*
G01Y378911D01*
G02X107711Y378037I-1000J0D01*
G03Y374885I-875J-1576D01*
G02X109196Y374011I485J-874D01*
G01Y372945D01*
X87342Y351091D01*
Y48393D01*
X96643Y39093D01*
X96676Y39037D01*
G03X101460Y36301I4756J2765D01*
G01X104303D01*
G02X105282Y35096I0J-1000D01*
G03X105254Y34948I1755J-409D01*
G03X105248Y34902I1784J-256D01*
G03X106569Y32947I1789J-215D01*
G03X108077Y33215I469J1740D01*
G02X109654Y32453I578J-817D01*
G01Y28461D01*
G02X108048Y27720I-999J55D01*
G03X105171Y26052I-1090J-1435D01*
G03X108628Y25607I1787J233D01*
G02X110247Y25903I912J-411D01*
G01X116316Y19834D01*
G02X116433Y19313I-354J-353D01*
G03X118678Y21558I3487J-1242D01*
G02X118157Y21675I-168J471D01*
G01X114498Y25334D01*
X113649Y26182D01*
X112378Y27454D01*
G02X112256Y27744I377J329D01*
G01Y35839D01*
G02X112756Y36301I500J-40D01*
G01X116384D01*
X116801Y36073D01*
X116869Y35975D01*
G03X117979Y34919I3051J2096D01*
G03X118439Y34678I1944J3150D01*
G03X119515Y34391I1481J3393D01*
G03X123606Y38414I405J3680D01*
G01Y38416D01*
X123604Y38440D01*
Y38698D01*
X126634Y41728D01*
X133970D01*
G02X134286Y41581I-40J-499D01*
G01X136371Y39496D01*
Y39128D01*
X136353Y39062D01*
Y39061D01*
G03X138929Y41638I3567J-990D01*
G01X138863Y41620D01*
X138495D01*
X136371Y43744D01*
G02X137078Y45451I707J707D01*
G01X137297D01*
X137440Y45322D01*
G03X140264Y44385I2480J2749D01*
G03X140286Y44387I-324J3688D01*
G03X142535Y45451I-367J3684D01*
G01X144188D01*
G02X144688Y44973I0J-501D01*
G01Y24680D01*
X141683Y21675D01*
G02X141162Y21558I-353J354D01*
G03X137229Y15529I-1242J-3487D01*
G03X143420Y19279I2692J2541D01*
G01X143406Y19317D01*
X143391Y19399D01*
G02X143530Y19840I493J87D01*
G01X143761Y20071D01*
X147290Y23601D01*
Y68198D01*
X147068Y68420D01*
X146920Y68569D01*
Y74535D01*
X143697Y77758D01*
X143621Y77944D01*
X143622Y78044D01*
G03X140327Y81751I-3702J27D01*
G01X140136Y81772D01*
X139882Y82056D01*
Y84086D01*
X140136Y84370D01*
X140327Y84391D01*
G03X143206Y89777I-407J3680D01*
G02X144039Y91238I887J462D01*
G01X156601D01*
G02X156917Y91091I-40J-499D01*
G01X158072Y89936D01*
G03X159051Y89415I1344J1345D01*
G02X159853Y88329I-193J-981D01*
G03X159837Y88130I1486J-220D01*
G01Y88116D01*
G03X159879Y87754I1502J-9D01*
G02X158905Y86519I-972J-235D01*
G03X158870I-18J-1502D01*
G03X157424Y85291I31J-1502D01*
G03X157515Y84439I1477J-273D01*
G03X160263Y84385I1386J578D01*
G03X160361Y85371I-1362J633D01*
G02X161335Y86606I972J235D01*
G03X161349I7J1502D01*
G03X161735Y86659I-10J1502D01*
G03X161825Y89529I-396J1449D01*
G02X161236Y90725I375J927D01*
G03X161318Y91237I-1819J554D01*
G03X160762Y92626I-1901J45D01*
G01X159156Y94231D01*
X158347Y95040D01*
X117816D01*
X114846Y98010D01*
Y319870D01*
G02X115346Y320370I500J0D01*
G01X115401D01*
G02X116362Y319094I0J-1000D01*
G03X123478I3558J-1023D01*
G02X124439Y320370I961J276D01*
G01X127622D01*
Y335773D01*
X127592D01*
G02X126885Y337480I0J1000D01*
G01X135336Y345930D01*
X143284D01*
X158136Y360782D01*
Y361799D01*
X158958Y362621D01*
Y370400D01*
G02X160408Y371293I1000J0D01*
G03X162749Y370617I2975J5912D01*
G03X163384Y370587I629J6588D01*
G03X170002Y377205I0J6618D01*
G03X169989Y377627I-6617J7D01*
G01Y377628D01*
G03X169982Y377727I-6604J-417D01*
G03X165633Y383430I-6598J-522D01*
G02X165266Y385077I340J940D01*
G01X173766Y393577D01*
Y442973D01*
X153079Y463660D01*
X119450D01*
X117402Y465708D01*
Y561652D01*
G02X118725Y562598I1000J0D01*
G03Y569606I1195J3504D01*
G02X117402Y570552I-323J946D01*
G01Y571652D01*
G02X118725Y572598I1000J0D01*
G03Y579606I1195J3504D01*
G02X117402Y580552I-323J946D01*
G01Y581652D01*
G02X118725Y582598I1000J0D01*
G03Y589606I1195J3504D01*
G02X117402Y590552I-323J946D01*
G01Y591652D01*
G02X118725Y592598I1000J0D01*
G03Y599606I1195J3504D01*
G02X117402Y600552I-323J946D01*
G01Y601652D01*
G02X118725Y602598I1000J0D01*
G03Y609606I1195J3504D01*
G02X117402Y610552I-323J946D01*
G01Y611652D01*
G02X118725Y612598I1000J0D01*
G03Y619606I1195J3504D01*
G02X117402Y620552I-323J946D01*
G01Y621652D01*
G02X118725Y622598I1000J0D01*
G03Y629606I1195J3504D01*
G02X117402Y630552I-323J946D01*
G01Y631652D01*
G02X118725Y632598I1000J0D01*
G03Y639606I1195J3504D01*
G02X117402Y640552I-323J946D01*
G01Y641652D01*
G02X118725Y642598I1000J0D01*
G03Y649606I1195J3504D01*
G02X117402Y650552I-323J946D01*
G01Y651652D01*
G02X118725Y652598I1000J0D01*
G03Y659606I1195J3504D01*
G02X117402Y660552I-323J946D01*
G01Y661652D01*
G02X118725Y662598I1000J0D01*
G03X122861Y663853I1195J3504D01*
G03X123598Y666525I-2941J2249D01*
G03X123473Y667142I-3678J-424D01*
G02X124439Y668400I966J258D01*
G01X127622D01*
Y683859D01*
G02X127768Y684212I500J0D01*
G01X135451Y691894D01*
X148805D01*
X161704Y704793D01*
Y715607D01*
G02X162763Y716605I1000J0D01*
G03X174003Y727203I622J10600D01*
G03X173971Y728039I-10617J12D01*
G03X170240Y735314I-10586J-835D01*
G02X170179Y736785I646J764D01*
G01X183190Y749796D01*
Y793470D01*
X151728Y824932D01*
Y833440D01*
X151660Y833508D01*
X151583Y833692D01*
Y834112D01*
X143691Y842004D01*
X120213D01*
X116267Y845950D01*
Y847474D01*
X116426Y847837D01*
X116491Y847903D01*
G03X117040Y849240I-1352J1336D01*
G01Y909879D01*
G02X118421Y910749I999J-55D01*
G03X123468Y915192I1499J3385D01*
G02X124434Y916449I966J257D01*
G01X135406D01*
G02X136372Y915192I0J-1000D01*
G03X143468I3548J-1058D01*
G02X144434Y916449I966J257D01*
G01X153687D01*
X159054Y921816D01*
X177486D01*
X183182Y927513D01*
Y967298D01*
X177655Y972824D01*
X177281D01*
G02X176815Y973143I0J500D01*
G03X173455I-1680J-653D01*
G02X172989Y972824I-466J181D01*
G01X169486D01*
X169204Y973071D01*
X169179Y973257D01*
G03X164816Y974573I-2480J-333D01*
G01X164748Y974496D01*
X164336Y974299D01*
X164148Y974358D01*
G03X162227Y973224I-449J-1434D01*
G01X162192Y973049D01*
X161916Y972824D01*
X158177D01*
X154100Y976900D01*
G02X153954Y977253I354J353D01*
G01Y1021216D01*
G02X155661Y1021923I1000J0D01*
G01X157086Y1020498D01*
X160933D01*
G02X161927Y1019621I1J-1000D01*
G03X163924Y1018321I1497J116D01*
G02X164479Y1018164I166J-472D01*
G03X168920Y1019566I1945J1573D01*
G02X169918Y1020498I998J-68D01*
G01X171049D01*
X171724Y1019824D01*
G03X173465Y1018620I4173J4174D01*
G02X173934Y1017234I-412J-912D01*
G03X175751Y1014516I1539J-938D01*
G03X176903Y1015199I-277J1780D01*
G03X177120Y1017028I-1430J1097D01*
G02X177724Y1018385I914J406D01*
G03X180369Y1027849I-1827J5612D01*
G02X180334Y1028456I379J326D01*
G03X171275Y1035939I-4886J3310D01*
G01X170689Y1035354D01*
X163241D01*
X159660Y1038935D01*
Y1070090D01*
G02X160982Y1071038I1000J1D01*
G03X163253Y1070588I2402J6167D01*
G03X163574Y1070589I140J6617D01*
G03X170003Y1077205I-190J6616D01*
G03X169982Y1077727I-6618J-5D01*
G03X169558Y1079590I-6598J-522D01*
G03X169054Y1080619I-6173J-2386D01*
G03X163353Y1083823I-5670J-3414D01*
G02X162699Y1085531I52J999D01*
G01X179714Y1102546D01*
Y1136996D01*
X155362Y1161348D01*
X118031D01*
X117115Y1162264D01*
G02X116968Y1162617I353J354D01*
G01Y1257942D01*
G02X118361Y1258807I999J-55D01*
G03Y1265523I1559J3358D01*
G02X116968Y1266388I-394J920D01*
G01Y1267942D01*
G02X118361Y1268807I999J-55D01*
G03Y1275523I1559J3358D01*
G02X116968Y1276388I-394J920D01*
G01Y1277942D01*
G02X118361Y1278807I999J-55D01*
G03Y1285523I1559J3358D01*
G02X116968Y1286388I-394J920D01*
G01Y1287942D01*
G02X118361Y1288807I999J-55D01*
G03Y1295523I1559J3358D01*
G02X116968Y1296388I-394J920D01*
G01Y1297942D01*
G02X118361Y1298807I999J-55D01*
G03Y1305523I1559J3358D01*
G02X116968Y1306388I-394J920D01*
G01Y1307942D01*
G02X118361Y1308807I999J-55D01*
G03Y1315523I1559J3358D01*
G02X116968Y1316388I-394J920D01*
G01Y1317942D01*
G02X118361Y1318807I999J-55D01*
G03Y1325523I1559J3358D01*
G02X116968Y1326388I-394J920D01*
G01Y1327942D01*
G02X118361Y1328807I999J-55D01*
G03Y1335523I1559J3358D01*
G02X116968Y1336388I-394J920D01*
G01Y1337942D01*
G02X118361Y1338807I999J-55D01*
G03Y1345523I1559J3358D01*
G02X116968Y1346388I-394J920D01*
G01Y1347942D01*
G02X118361Y1348807I999J-55D01*
G03Y1355523I1559J3358D01*
G02X116968Y1356388I-394J920D01*
G01Y1357942D01*
G02X118361Y1358807I999J-55D01*
G03Y1365523I1559J3358D01*
G02X116968Y1366388I-394J920D01*
G01Y1368002D01*
G02X117430Y1368464I500J-38D01*
G01X123622D01*
Y1375866D01*
X120382D01*
G02X119730Y1377574I54J999D01*
G01X130072Y1387916D01*
X151639D01*
X157481Y1393758D01*
Y1396649D01*
G02X158530Y1397648I1000J0D01*
G03Y1401248I88J1800D01*
G02X157481Y1402247I-49J999D01*
G01Y1414141D01*
X157896Y1414556D01*
X159173D01*
X161347Y1416730D01*
X161645D01*
X161685Y1416724D01*
G03X174003Y1427206I1700J10481D01*
G03X173969Y1428044I-10618J-11D01*
G03X162477Y1437785I-10585J-839D01*
G02X161392Y1438781I-85J996D01*
G01Y1445410D01*
X161676Y1445859D01*
X161800Y1445922D01*
G03Y1456288I-2608J5183D01*
G01X161676Y1456351D01*
X161392Y1456800D01*
Y1471752D01*
G02X161669Y1472200I500J0D01*
G03X164217Y1479417I-2453J4924D01*
G02X164270Y1479923I455J208D01*
G03X155353Y1487607I-4744J3511D01*
G01X151832Y1484086D01*
X146123D01*
X143321Y1486888D01*
X119059D01*
G02X118755Y1487023I40J499D01*
G01X117444Y1488334D01*
X114863Y1490916D01*
G03X112429Y1491130I-1345J-1345D01*
G02X111802Y1491173I-287J410D01*
G01X111788Y1491187D01*
G02X111628Y1491553I340J367D01*
G01Y1721440D01*
G02X111774Y1721793I500J0D01*
G01X137575Y1747590D01*
X148091D01*
X156514Y1756013D01*
Y1772349D01*
G02X158284Y1772986I1000J-1D01*
G03X170003Y1777205I5100J4219D01*
G03X169982Y1777727I-6618J-5D01*
G03X158284Y1781424I-6598J-522D01*
G02X156514Y1782061I-770J638D01*
G01Y1798589D01*
G02X156891Y1799074I500J0D01*
G01X156892D01*
G03Y1802568I-440J1747D01*
G01X156891D01*
G02X156514Y1803053I123J485D01*
G01Y1817808D01*
X150552Y1823771D01*
G02X151259Y1825478I707J707D01*
G01X156796D01*
G02X157217Y1825249I1J-500D01*
G03X157625Y1824694I4628J2975D01*
G03X158166Y1823891I1450J393D01*
G03X158486Y1823705I909J1196D01*
G03X158865Y1823600I587J1383D01*
G03X164335Y1823320I2979J4625D01*
G03X165669Y1832180I-2491J4906D01*
G03X165499Y1832993I-5847J-798D01*
G03X159822Y1837282I-5677J-1613D01*
G01X106233D01*
X89632Y1820680D01*
Y1748618D01*
X89866Y1748384D01*
Y1741923D01*
X89244Y1741301D01*
Y1628129D01*
X87172Y1626057D01*
X84634D01*
G02X84281Y1626203I0J500D01*
G01X58908Y1651577D01*
Y1761733D01*
X53532Y1767109D01*
G02X53387Y1767497I354J353D01*
G01Y1767503D01*
G03X38701Y1773506I-8331J583D01*
G02X37299Y1773388I-761J649D01*
G01X30088D01*
X29712Y1773559D01*
X29642Y1773638D01*
G03X23216Y1776437I-6240J-5551D01*
G02X22194Y1777437I-22J1000D01*
G01Y1808987D01*
X22569Y1809362D01*
X22817D01*
X22834Y1809361D01*
G03X26651Y1809999I569J8332D01*
G03X31750Y1817452I-3249J7694D01*
G02X32250Y1817938I500J-14D01*
G01X36204D01*
G02X36704Y1817438I0J-500D01*
G01Y1809342D01*
X53408D01*
Y1826044D01*
X44202D01*
X41706Y1828540D01*
X14210D01*
X7711Y1822041D01*
G02X6004Y1822748I-707J707D01*
G01Y2064362D01*
G02X6504Y2064862I500J0D01*
G01X92520D01*
G03X104429Y2076772I0J11909D01*
G01Y2080110D01*
G02X104929Y2080610I500J0D01*
G01X397638D01*
G02X399508Y2078740I0J-1870D01*
G01Y862746D01*
G02X397801Y862039I-1000J0D01*
G01X387374Y872466D01*
Y1106893D01*
X392030Y1111549D01*
Y1145703D01*
X369442Y1168291D01*
G02X369318Y1168583I375J332D01*
G01Y1202250D01*
G02X370748Y1203098I999J-55D01*
G03Y1206352I775J1627D01*
G02X369318Y1207200I-431J903D01*
G01Y1208981D01*
G02X369464Y1209334I500J0D01*
G01X392918Y1232787D01*
Y1337156D01*
X393742Y1337980D01*
X394396Y1338635D01*
Y1362340D01*
G03X393916Y1363968I-3001J0D01*
G03X393020Y1364864I-2522J-1626D01*
G03X391956Y1365289I-1625J-2524D01*
G03X391103Y1365327I-559J-2949D01*
G01X391079Y1365325D01*
X390817D01*
X389178Y1366964D01*
Y1376032D01*
X389418Y1376272D01*
Y1376798D01*
X389486Y1376914D01*
G03X389542Y1377019I-1473J853D01*
G03X389617Y1377195I-1525J754D01*
G03X389632Y1377237I-1595J593D01*
G03X389718Y1377774I-1615J534D01*
G01Y1379643D01*
G02X389904Y1380032I500J0D01*
G03X391018Y1382366I-1888J2334D01*
G01Y1849676D01*
X375062Y1865632D01*
Y1892252D01*
X377432Y1894622D01*
Y1899284D01*
G02X377484Y1899468I499J-42D01*
G01X378777D01*
G03Y1904028I0J2280D01*
G01X375906D01*
G02X375848Y1905495I649J760D01*
G01X375936Y1905583D01*
Y1909066D01*
X372921Y1912081D01*
X362289D01*
X361928Y1912441D01*
X361908Y1912615D01*
G03X360322Y1914201I-1790J-204D01*
G01X360148Y1914221D01*
X359381Y1914989D01*
X356576Y1917794D01*
Y1918742D01*
G02X357076Y1919242I500J0D01*
G01X357222D01*
X357346Y1919163D01*
G03X358241Y1918880I972J1517D01*
G03X358587Y1918898I80J1800D01*
G03X360106Y1920905I-269J1782D01*
G03X357840Y1922418I-1788J-225D01*
G02X356576Y1923382I-264J964D01*
G01Y1942135D01*
X355813Y1942898D01*
X355042Y1943668D01*
G02X354906Y1944125I353J354D01*
G01Y1944126D01*
G03X353294Y1947269I-2741J579D01*
G03X353169Y1947321I-1138J-2560D01*
G02X352807Y1948938I366J931D01*
G01X352932Y1949063D01*
G02X354549Y1948701I686J-728D01*
G03X354653Y1948463I2617J1002D01*
G03X359961Y1949515I2512J1241D01*
G03X354895Y1951348I-2796J191D01*
G03X354451Y1950401I2270J-1642D01*
G01Y1950400D01*
G02X353967Y1950025I-484J125D01*
G01X353966D01*
G02X353466Y1950525I0J500D01*
G01Y1951938D01*
G02X353693Y1952357I500J0D01*
G03X350637I-1528J2348D01*
G02X350864Y1951938I-273J-419D01*
G01Y1950678D01*
X350684Y1950496D01*
X350634Y1950446D01*
G02X349808Y1950634I-354J354D01*
G03X346585Y1952446I-2643J-929D01*
G03X346037Y1952270I578J-2741D01*
G03X345000Y1951484I1128J-2565D01*
G03X344388Y1949329I2165J-1779D01*
G03X344954Y1947983I2777J376D01*
G03X346672Y1946947I2210J1723D01*
G02X347084Y1946455I-88J-492D01*
G01Y1943406D01*
X352424Y1938066D01*
Y1915464D01*
X352315Y1915327D01*
G03X352026Y1914803I1412J-1120D01*
G03X351925Y1914157I1700J-597D01*
G03X353522Y1912415I1801J48D01*
G01X353696Y1912395D01*
X355800Y1910291D01*
Y1908920D01*
G02X355300Y1908458I-500J40D01*
G01X350781D01*
Y1905513D01*
X350753Y1905433D01*
G03X350699Y1905220I1230J-425D01*
G03X350690Y1905157I1284J-216D01*
G03X350685Y1905102I1293J-145D01*
G03X350682Y1905006I1298J-89D01*
G01Y1900658D01*
X350614Y1900590D01*
Y1896107D01*
X350446Y1895938D01*
X348000Y1893492D01*
Y1877926D01*
X347075Y1877001D01*
X346901Y1876981D01*
G03X345804Y1873945I204J-1790D01*
G01Y1869036D01*
X333628Y1856860D01*
Y1803558D01*
X349426Y1787760D01*
Y1787499D01*
G02X348659Y1787076I-500J0D01*
G03X344795Y1786200I-1494J-2371D01*
G03X344383Y1784367I2370J-1495D01*
G03X345658Y1782343I2781J339D01*
G03X346859Y1781920I1507J2362D01*
G01X347050Y1781899D01*
X347304Y1781615D01*
Y1777795D01*
X347050Y1777511D01*
X346859Y1777490D01*
G03X349879Y1774009I306J-2785D01*
G01Y1774010D01*
G02X350363Y1774385I484J-125D01*
G01X350364D01*
G02X350864Y1773885I0J-500D01*
G01Y1772472D01*
G02X350637Y1772053I-500J0D01*
G03X353693I1528J-2348D01*
G02X353466Y1772472I273J419D01*
G01Y1773885D01*
G02X353966Y1774385I500J0D01*
G01X353967D01*
G02X354451Y1774010I0J-500D01*
G01Y1774009D01*
G03Y1775401I2714J696D01*
G01Y1775400D01*
G02X353967Y1775025I-484J125D01*
G01X353966D01*
G02X353466Y1775525I0J500D01*
G01Y1775847D01*
G02X353679Y1777347I753J658D01*
G03X354615Y1778345I-1514J2358D01*
G03X354791Y1778728I-2451J1358D01*
G03X353693Y1782053I-2626J977D01*
G02X353466Y1782472I273J419D01*
G01Y1783885D01*
G02X353966Y1784385I500J0D01*
G01X353967D01*
G02X354451Y1784010I0J-500D01*
G01Y1784009D01*
G03X354895Y1783063I2714J697D01*
G03X356076Y1782123I2271J1641D01*
G03X359844Y1783883I1089J2582D01*
G03X355176Y1786679I-2679J823D01*
G02X353466Y1787329I-711J704D01*
G01Y1789705D01*
X337630Y1805541D01*
Y1854995D01*
G02X337776Y1855348I500J0D01*
G01X354552Y1872123D01*
Y1873050D01*
X354661Y1873186D01*
G03X354751Y1873311I-1416J1114D01*
G03X354984Y1874799I-1501J997D01*
G03X354744Y1875316I-1734J-491D01*
G03X354661Y1875429I-1493J-1009D01*
G01X354552Y1875566D01*
Y1876164D01*
X355844Y1877456D01*
Y1878054D01*
G02X356344Y1878554I500J0D01*
G01X357858D01*
G02X358358Y1878054I0J-500D01*
G01Y1876524D01*
X358916Y1875966D01*
X359042Y1875841D01*
X359229Y1875654D01*
X359249Y1875480D01*
G03X360835Y1873894I1790J204D01*
G01X361009Y1873874D01*
X361545Y1873337D01*
X362076Y1872806D01*
Y1865367D01*
X380672Y1846771D01*
G02X380794Y1846481I-377J-329D01*
G01Y1786611D01*
G02X378963Y1786109I-999J54D01*
G03Y1778931I-5578J-3589D01*
G02X380794Y1778429I832J-556D01*
G01Y1645100D01*
G02X380648Y1644747I-500J0D01*
G01X349024Y1613124D01*
Y1612715D01*
G02X348524Y1612215I-500J0D01*
G01X348411D01*
G03X348174Y1612319I-1243J-2511D01*
G03X345766Y1612133I-1009J-2614D01*
G03X345098Y1611597I1399J-2428D01*
G03X344689Y1608393I2066J-1892D01*
G03X347045Y1606906I2476J1312D01*
G02X347524Y1606406I-21J-500D01*
G01Y1603004D01*
G02X347045Y1602504I-500J0D01*
G03X346257Y1602356I118J-2799D01*
G03X345868Y1602189I908J-2651D01*
G03X345262Y1601762I1297J-2484D01*
G03X347890Y1596998I1902J-2058D01*
G03X347935Y1597011I-755J2698D01*
G03X347983Y1597025I-761J2697D01*
G03X348003Y1597031I-795J2687D01*
G02X349280Y1596125I278J-961D01*
G01Y1595750D01*
X349288Y1595742D01*
G02X349424Y1595285I-353J-354D01*
G01Y1595284D01*
G03X354361Y1592965I2741J-579D01*
G03X354602Y1593322I-2195J1741D01*
G03X352350Y1597501I-2437J1383D01*
G02X351882Y1598000I32J499D01*
G01Y1601410D01*
G02X352349Y1601909I500J0D01*
G03X352852Y1601988I-181J2796D01*
G03X353337Y1607250I-687J2717D01*
G02X353046Y1607704I209J454D01*
G01Y1611278D01*
G02X353192Y1611631I500J0D01*
G01X383338Y1641776D01*
G02X385016Y1641095I679J-736D01*
G01Y1382366D01*
G03X386130Y1380032I3002J0D01*
G02X386316Y1379643I-314J-389D01*
G01Y1378686D01*
G02X386169Y1378332I-500J0D01*
G01X385919Y1378083D01*
X385774Y1377938D01*
Y1374207D01*
G02X385274Y1373707I-500J0D01*
G01X384160D01*
G02X383660Y1374207I0J500D01*
G01Y1374266D01*
X383558Y1374367D01*
X382082Y1375843D01*
G02X381989Y1376421I354J353D01*
G03X382074Y1377837I-1611J807D01*
G03X381788Y1378350I-1696J-609D01*
G01X381680Y1378487D01*
Y1387339D01*
X352744Y1416275D01*
Y1416584D01*
G02X353080Y1417057I500J1D01*
G01X353081D01*
G03X354548Y1418232I-917J2648D01*
G03X353074Y1422356I-2383J1474D01*
G02X352701Y1424005I334J942D01*
G01X352865Y1424169D01*
G02X354514Y1423796I707J-707D01*
G03X354677Y1423416I2650J912D01*
G03X357207Y1421903I2488J1289D01*
G03X358797Y1422427I-42J2802D01*
G03X354451Y1425401I-1632J2278D01*
G01Y1425400D01*
G02X353967Y1425025I-484J125D01*
G01X353966D01*
G02X353466Y1425525I0J500D01*
G01Y1426938D01*
G02X353693Y1427357I500J0D01*
G03X350637I-1528J2348D01*
G02X350864Y1426938I-273J-419D01*
G01Y1425851D01*
X350665Y1425650D01*
X350587Y1425572D01*
G02X349880I-353J354D01*
G01X349806Y1425646D01*
X349768Y1425741D01*
G03X348177Y1427318I-2604J-1036D01*
G03X347083Y1427506I-1012J-2613D01*
G03X344938Y1426406I82J-2801D01*
G03X346828Y1421923I2227J-1701D01*
G01X347017Y1421900D01*
X347268Y1421617D01*
Y1415909D01*
X377404Y1385774D01*
G02X377550Y1385421I-354J-353D01*
G01Y1385246D01*
G02X377252Y1384789I-500J0D01*
G03X376682Y1381896I732J-1647D01*
G01Y1374752D01*
X375938Y1374008D01*
Y1373999D01*
X375646Y1373707D01*
X370920D01*
Y1370763D01*
X370892Y1370683D01*
G03X370820Y1370255I1230J-427D01*
G01Y1366956D01*
X368630Y1364765D01*
Y1343759D01*
X371689Y1340700D01*
X371709Y1340526D01*
G03X373295Y1338940I1790J204D01*
G01X373469Y1338920D01*
X374433Y1337956D01*
X374617Y1337771D01*
X375386Y1337002D01*
Y1331526D01*
X378756Y1328156D01*
Y1322964D01*
X380658Y1321062D01*
Y1290621D01*
X361651Y1271614D01*
X356165D01*
X350450Y1265899D01*
Y1262743D01*
G02X348870Y1261929I-1000J0D01*
G03X348652Y1262080I-1703J-2226D01*
G03X347548Y1262481I-1487J-2375D01*
G03X344960Y1257976I-384J-2775D01*
G03X345006Y1257919I2203J1731D01*
G03X346424Y1257003I2159J1786D01*
G02X346792Y1256521I-132J-482D01*
G01Y1252889D01*
G02X346424Y1252407I-500J0D01*
G03X344389Y1249327I741J-2702D01*
G03X344920Y1248028I2776J377D01*
G03X346698Y1246942I2245J1677D01*
G03X347345Y1246909I465J2763D01*
G03X349839Y1248869I-180J2796D01*
G01X349876Y1248986D01*
X349963Y1249073D01*
G02X350671I354J-353D01*
G01X350864Y1248880D01*
Y1247472D01*
G02X350637Y1247053I-500J0D01*
G03X353693I1528J-2348D01*
G02X353466Y1247472I273J419D01*
G01Y1248885D01*
G02X353966Y1249385I500J0D01*
G01X353967D01*
G02X354451Y1249010I0J-500D01*
G01Y1249009D01*
G03X355148Y1247760I2714J696D01*
G03X356555Y1246970I2017J1945D01*
G03X359967Y1249740I610J2735D01*
G03X354582Y1250791I-2802J-35D01*
G02X352953Y1250472I-922J388D01*
G01X352932Y1250493D01*
G02X353251Y1252122I707J707D01*
G03X354771Y1255736I-1086J2583D01*
G01X354736Y1255824D01*
Y1256182D01*
G02X356087Y1257119I1000J0D01*
G03Y1262291I1078J2586D01*
G02X354736Y1263228I-351J937D01*
G01Y1264434D01*
X357850Y1267548D01*
X363335D01*
X381861Y1286073D01*
G02X383380Y1285900I687J-727D01*
G01Y1237239D01*
X360174Y1214033D01*
Y1163925D01*
X382722Y1141378D01*
G02X382868Y1141025I-354J-353D01*
G01Y1115605D01*
X361493Y1094230D01*
X355203D01*
X349662Y1088690D01*
Y1087569D01*
G02X348407Y1087217I-832J554D01*
G03X346803Y1087484I-1242J-2512D01*
G03X345857Y1082227I362J-2779D01*
G03X346444Y1081997I1309J2477D01*
G02X346815Y1081515I-129J-483D01*
G01X346816Y1081209D01*
X346700Y1080932D01*
Y1078075D01*
X346705Y1078070D01*
Y1077658D01*
X346469Y1077422D01*
X346349Y1077386D01*
G03X345182Y1072725I816J-2681D01*
G03X349737Y1073593I1983J1980D01*
G01X349796Y1073731D01*
X350046Y1073895D01*
X350196D01*
G02X350696Y1073395I0J-500D01*
G01Y1072356D01*
G02X350494Y1071954I-500J0D01*
G03X353836I1671J-2249D01*
G02X353634Y1072356I298J402D01*
G01Y1073395D01*
G02X354134Y1073895I500J0D01*
G01X354284D01*
X354533Y1073732D01*
X354593Y1073593D01*
G03X354651Y1073468I2570J1116D01*
G03X359951Y1075007I2514J1237D01*
G03X359593Y1076104I-2786J-302D01*
G03X354702Y1076042I-2428J-1398D01*
G02X353116Y1075812I-879J477D01*
G01X352842Y1076086D01*
G02X353387Y1077183I980J197D01*
G03X354213Y1081618I-1222J2522D01*
G01X354078Y1081763D01*
Y1082652D01*
G02X354578Y1083152I500J0D01*
G01X354693D01*
X354899Y1083053D01*
X354970Y1082963D01*
G03Y1086447I2195J1742D01*
G01X354899Y1086357D01*
X354693Y1086258D01*
X354578D01*
G02X354078Y1086758I0J500D01*
G01Y1087068D01*
X356972Y1089962D01*
X363261D01*
X379684Y1106384D01*
G02X381370Y1105657I686J-727D01*
G01Y869980D01*
X394288Y857062D01*
G02X394412Y856763I-375J-331D01*
G01Y855988D01*
X394411Y855882D01*
G02X392725Y855155I-1000J0D01*
G01X357308Y890571D01*
G02X357182Y890873I374J333D01*
G01Y891528D01*
X355042Y893668D01*
G02X354906Y894125I353J354D01*
G01Y894126D01*
G03X352920Y897403I-2741J579D01*
G03X352826Y897428I-767J-2694D01*
G02X352610Y898285I119J486D01*
G01X352614Y898289D01*
Y901708D01*
X352811Y901973D01*
X352970Y902021D01*
G03X353081Y902057I-809J2683D01*
G03X352137Y907507I-916J2648D01*
G03X349912Y903038I28J-2802D01*
G01X350010Y902906D01*
Y902364D01*
G02X349702Y901903I-500J1D01*
G01X349311Y901740D01*
X348943Y901872D01*
X348880Y901920D01*
G03X345641Y902056I-1715J-2215D01*
G03X345495Y901955I1520J-2353D01*
G03X344368Y899880I1669J-2250D01*
G03X346611Y896958I2797J-175D01*
G01X346787Y896923D01*
X347012Y896647D01*
Y891267D01*
X347742Y890536D01*
X350412Y887866D01*
X354352D01*
X390794Y851424D01*
G02X390916Y851134I-377J-329D01*
G01Y761158D01*
X383636Y753878D01*
Y728315D01*
X369352Y714031D01*
Y700729D01*
X364341Y695718D01*
X363789D01*
X363653Y695827D01*
G03X360741Y694621I-1122J-1410D01*
G01X360721Y694447D01*
X360224Y693950D01*
X359891Y693618D01*
X359732Y693459D01*
Y687578D01*
X357816Y685662D01*
Y683938D01*
G02X357316Y683438I-500J0D01*
G01X355802D01*
G02X355302Y683938I0J500D01*
G01Y697260D01*
X355120Y697442D01*
X354738Y697823D01*
X354168Y698393D01*
X354148Y698567D01*
G03X352562Y700153I-1790J-204D01*
G01X352388Y700173D01*
X352040Y700522D01*
Y716424D01*
G02X352483Y716921I500J0D01*
G03X352542Y716928I-301J2786D01*
G03X352562Y716931I-406J2772D01*
G03X353279Y722277I-396J2774D01*
G02X352969Y723901I397J917D01*
G01X352970Y723902D01*
G02X354594Y723592I707J-707D01*
G03X359946Y725058I2572J1112D01*
G03X354452Y725405I-2780J-352D01*
G01X354410Y725239D01*
X354139Y725029D01*
X353968D01*
G02X353468Y725529I0J500D01*
G01Y726938D01*
X353694Y727353D01*
X353789Y727420D01*
G03X350543I-1623J2285D01*
G01X350638Y727353D01*
X350864Y726938D01*
Y725478D01*
X350684Y725298D01*
X350537Y725151D01*
X350124Y725150D01*
X349887Y725387D01*
X349851Y725508D01*
G03X345617Y727040I-2685J-803D01*
G03X345076Y726572I1548J-2336D01*
G03X345846Y722233I2090J-1867D01*
G02X346069Y720683I-504J-864D01*
G01X346046Y720660D01*
X345926Y720539D01*
Y720233D01*
G02X345426Y719733I-500J0D01*
G01X345239D01*
X344957Y719978D01*
X344931Y720162D01*
G03X344929Y720173I-2756J-495D01*
G03X344164Y721670I-2763J-468D01*
G03X340275Y721773I-1998J-1965D01*
G03X339650Y720939I1891J-2068D01*
G03X344200Y717777I2516J-1235D01*
G02X345926Y717144I727J-687D01*
G01Y695324D01*
G03X347023Y692288I1301J-1246D01*
G01X347197Y692268D01*
X347450Y692014D01*
X348378Y691086D01*
Y669950D01*
X350885Y667443D01*
Y653806D01*
X351554Y653137D01*
Y649926D01*
G02X351054Y649426I-500J0D01*
G01X350750D01*
X333024Y631700D01*
Y607091D01*
G02X332878Y606738I-500J0D01*
G01X324647Y598508D01*
G02X323520Y599335I-140J990D01*
G03X321448Y597263I-1778J-294D01*
G02X322275Y596136I-163J-987D01*
G01X321756Y595616D01*
Y583774D01*
G02X320386Y583553I-800J601D01*
G03X317894Y583232I-1081J-1441D01*
G03X320644Y580905I1410J-1122D01*
G02X322062Y580908I710J-704D01*
G01X341656Y561313D01*
Y557685D01*
X341465Y557423D01*
X341309Y557373D01*
G03X339922Y553027I857J-2668D01*
G03X344667Y553441I2244J1678D01*
G02X345701Y553980I893J-451D01*
G01X345975Y553706D01*
G02X345767Y552133I-707J-707D01*
G03X344378Y549986I1399J-2428D01*
G03X344438Y549064I2788J-282D01*
G03X347053Y546905I2728J641D01*
G03X348501Y547241I113J2800D01*
G03X349439Y548066I-1335J2464D01*
G03X349484Y548130I-2270J1644D01*
G01X349550Y548228D01*
X349987Y548470D01*
X350273Y548406D01*
G02X350664Y547918I-109J-488D01*
G01Y547331D01*
X350469Y546938D01*
X350386Y546870D01*
G03X353946I1780J-2165D01*
G01X353863Y546938D01*
X353668Y547331D01*
Y547918D01*
G02X354059Y548406I500J0D01*
G01X354346Y548470D01*
X354781Y548229D01*
X354848Y548130D01*
G03X359958Y549944I2318J1575D01*
G03X354703Y551041I-2792J-239D01*
G02X353117Y550810I-879J477D01*
G01X352801Y551126D01*
G02X353364Y552172I990J142D01*
G03X353372Y552176I-1249J2508D01*
G03X354943Y555081I-1206J2529D01*
G03X353788Y556990I-2777J-376D01*
G01X353694Y557057D01*
X353468Y557472D01*
Y558881D01*
G02X353968Y559381I500J0D01*
G01X354139D01*
X354409Y559172D01*
X354452Y559005D01*
G03Y560405I2714J700D01*
G01Y560404D01*
G02X353968Y560029I-484J125D01*
G01X353760D01*
X353468Y560321D01*
Y560675D01*
X353243Y560899D01*
X349988Y564154D01*
X345011D01*
X326136Y583029D01*
Y593801D01*
X337404Y605069D01*
Y628991D01*
G02X337550Y629344I500J0D01*
G01X352031Y643824D01*
X359504D01*
X363335Y647655D01*
X364383Y648704D01*
X364557Y648724D01*
G03X366117Y650881I-204J1790D01*
G01Y650882D01*
G02X366253Y651337I490J102D01*
G01X368096Y653180D01*
Y653242D01*
X368388Y653534D01*
X370556D01*
Y656478D01*
X370584Y656558D01*
G03X370656Y656986I-1230J427D01*
G01Y661691D01*
X369798Y662549D01*
X368930Y663416D01*
X363508D01*
G02X363046Y663878I38J500D01*
G01Y670478D01*
G02X363900Y670832I500J0D01*
G01X364432Y670300D01*
X373100D01*
G02X373600Y669800I0J-500D01*
G01Y667159D01*
X375358Y665400D01*
G02X375504Y665066I-354J-354D01*
G03X376454Y662891I3248J124D01*
G01X383388Y655957D01*
Y341051D01*
X386690Y337749D01*
Y333153D01*
X386327Y332790D01*
X385146D01*
G03X384174Y332569I1J-2251D01*
G01X384072Y332520D01*
X382917D01*
G02X382417Y333020I0J500D01*
G01Y335070D01*
X379413D01*
Y334970D01*
X373097D01*
X372934Y334807D01*
X372255D01*
X371457Y334009D01*
G02X370749I-354J353D01*
G01X369557Y335201D01*
X369329Y335430D01*
X368378Y336381D01*
Y338854D01*
G03Y341346I-1302J1246D01*
G01Y343960D01*
X354040Y358298D01*
Y367411D01*
G02X354180Y367759I500J1D01*
G03X354959Y369921I-2015J1947D01*
G03X353545Y372144I-2794J-216D01*
G02X353321Y373694I503J864D01*
G01X353344Y373718D01*
X353466Y373840D01*
Y373885D01*
G02X353966Y374385I500J0D01*
G01X353967D01*
G02X354451Y374010I0J-500D01*
G01Y374009D01*
G03Y375401I2714J696D01*
G01Y375400D01*
G02X353967Y375025I-484J125D01*
G01X353966D01*
G02X353466Y375525I0J500D01*
G01Y376938D01*
G02X353693Y377357I500J0D01*
G03X350637I-1528J2348D01*
G02X350864Y376938I-273J-419D01*
G01Y375525D01*
G02X350364Y375025I-500J0D01*
G01X350363D01*
G02X349879Y375400I0J500D01*
G01Y375401D01*
G03X348697Y377051I-2714J-696D01*
G03X344564Y373663I-1532J-2346D01*
G03X345008Y372916I2602J1041D01*
G03X346735Y371936I2157J1789D01*
G02X347158Y371442I-77J-494D01*
G01Y365966D01*
X349792Y363332D01*
Y355602D01*
X361510Y343883D01*
Y341913D01*
X360719Y341122D01*
X360503Y340905D01*
X360329Y340885D01*
G03X359232Y337849I204J-1790D01*
G01Y336831D01*
X359614Y336448D01*
X361012Y335050D01*
G02X360305Y333343I-707J-707D01*
G01X358475D01*
Y330398D01*
X358447Y330318D01*
G03X358393Y330105I1230J-425D01*
G03X358384Y330042I1284J-216D01*
G03X358379Y329987I1293J-145D01*
G03X358376Y329891I1298J-89D01*
G01Y318952D01*
X356981Y317557D01*
Y311939D01*
X356154Y311112D01*
Y301802D01*
X356023Y301572D01*
X355910Y301505D01*
G03X355832Y301455I933J-1541D01*
G03X356627Y298166I1000J-1499D01*
G01X356801Y298146D01*
X357254Y297693D01*
Y292355D01*
G02X357108Y292002I-500J0D01*
G01X334614Y269509D01*
Y226672D01*
X347172Y214114D01*
G02X346637Y212457I-736J-677D01*
G03X345471Y211937I528J-2752D01*
G03X347167Y206903I1694J-2232D01*
G01X347171D01*
G02X347670Y206403I-1J-500D01*
G01Y203007D01*
G02X347169Y202507I-500J0D01*
G03X344797Y198207I-4J-2802D01*
G03X344862Y198108I2374J1488D01*
G03X349879Y199009I2303J1597D01*
G01Y199010D01*
G02X350363Y199385I484J-125D01*
G01X350364D01*
G02X350864Y198885I0J-500D01*
G01Y197472D01*
G02X350637Y197053I-500J0D01*
G03X353693I1528J-2348D01*
G02X353466Y197472I273J419D01*
G01Y198885D01*
G02X353966Y199385I500J0D01*
G01X353967D01*
G02X354451Y199010I0J-500D01*
G01Y199009D01*
G03Y200401I2714J696D01*
G01Y200400D01*
G02X353967Y200025I-484J125D01*
G01X353966D01*
G02X353466Y200525I0J500D01*
G01Y200602D01*
X353444Y200625D01*
X353362Y200707D01*
G02X353530Y202258I707J708D01*
G03X353784Y206992I-1365J2447D01*
G01X353690Y207059D01*
X353466Y207469D01*
Y208885D01*
G02X353966Y209385I500J0D01*
G01X353967D01*
G02X354451Y209010I0J-500D01*
G01Y209009D01*
G03X354895Y208063I2714J697D01*
G03X356076Y207123I2271J1641D01*
G03X359844Y208883I1089J2582D01*
G03X355176Y211679I-2679J823D01*
G02X353466Y212329I-711J704D01*
G01Y213621D01*
X338716Y228371D01*
Y267603D01*
G02X338862Y267956I500J0D01*
G01X361356Y290449D01*
Y296668D01*
X361717Y297030D01*
X362257Y297570D01*
X362431Y297590D01*
G03X362627Y301137I-204J1790D01*
G01X362455Y301176D01*
X362238Y301450D01*
Y302286D01*
X363391Y303439D01*
X365552D01*
G02X366052Y302939I0J-500D01*
G01Y302868D01*
X366920Y302000D01*
G02X366996Y301391I-354J-353D01*
G03X368242Y298693I1548J-922D01*
G01X368400Y298666D01*
X368824Y298242D01*
Y287289D01*
X381532Y274581D01*
Y141874D01*
X330918Y91260D01*
Y65868D01*
G02X330772Y65515I-500J0D01*
G01X323384Y58128D01*
Y45868D01*
X329823Y39430D01*
X347450D01*
X347992Y38888D01*
G02X347118Y37507I-924J-382D01*
G03X345185Y36687I48J-2802D01*
G03X344374Y34951I1980J-1982D01*
G03X346796Y31927I2791J-247D01*
G02X347230Y31431I-66J-496D01*
G01Y27979D01*
G02X346796Y27483I-500J0D01*
G03X345405Y26885I370J-2777D01*
G03X345519Y22438I1760J-2180D01*
G03X346632Y21954I1647J2266D01*
G03X347393Y21912I533J2751D01*
G03X349408Y23025I-228J2793D01*
G03X349749Y23621I-2243J1679D01*
G03X349815Y23795I-2585J1080D01*
G02X350288Y24133I473J-162D01*
G01X350496D01*
X350788Y23841D01*
Y22420D01*
X350575Y22015D01*
X350485Y21947D01*
G03X353845I1680J-2242D01*
G01X353755Y22015D01*
X353542Y22420D01*
Y23633D01*
G02X354042Y24133I500J0D01*
G01X354203D01*
X354463Y23948D01*
X354515Y23795D01*
G03X357527Y27484I2650J910D01*
G03X354464Y25451I-362J-2779D01*
G01X354429Y25324D01*
X354336Y25231D01*
G02X353628I-354J353D01*
G01X353396Y25463D01*
Y25532D01*
X352984Y25944D01*
G02X353450Y27215I924J382D01*
G03X353602Y27299I-1279J2493D01*
G03X354940Y29315I-1437J2406D01*
G03X354900Y30315I-2775J390D01*
G03X353693Y32053I-2734J-611D01*
G02X353466Y32472I273J419D01*
G01Y33885D01*
G02X353966Y34385I500J0D01*
G01X353967D01*
G02X354451Y34010I0J-500D01*
G01Y34009D01*
G03X354895Y33063I2714J697D01*
G03X356076Y32123I2271J1641D01*
G03X359844Y33883I1089J2582D01*
G03X355176Y36679I-2679J823D01*
G02X353466Y37329I-711J704D01*
G01Y39195D01*
X351294Y41368D01*
X349144Y43518D01*
X331517D01*
X327594Y47441D01*
G02X327472Y47731I377J329D01*
G01Y56434D01*
X331331Y60293D01*
X332043Y61004D01*
X335006Y63967D01*
Y89566D01*
X385620Y140180D01*
Y276275D01*
X372912Y288983D01*
Y296847D01*
X375244Y299179D01*
Y299265D01*
X375353Y299402D01*
G03X375368Y299421I-1407J1126D01*
G03X375619Y299865I-1427J1100D01*
G03X375716Y300842I-1677J660D01*
G03X374290Y302292I-1774J-318D01*
G01X374004Y302348D01*
X373886Y302466D01*
Y303255D01*
G02X374274Y303439I388J-317D01*
G01X376233D01*
Y306384D01*
X376261Y306464D01*
G03X376315Y306677I-1230J425D01*
G03X376324Y306740I-1284J216D01*
G03X376329Y306795I-1293J145D01*
G03X376332Y306891I-1298J89D01*
G01Y312272D01*
X376102Y312503D01*
X375706Y312899D01*
G02Y313607I353J354D01*
G01X376274Y314175D01*
Y324420D01*
G02X376774Y324920I500J0D01*
G01X379831D01*
X382412Y327501D01*
Y328016D01*
G02X382912Y328516I500J0D01*
G01X384156D01*
X384251Y328475D01*
G03X385146Y328288I898J2063D01*
G01X388191D01*
X389729Y329826D01*
G02X390063Y329972I354J-354D01*
G03X393190Y333220I-123J3248D01*
G01Y340441D01*
X389888Y343743D01*
Y658649D01*
X381050Y667487D01*
G03X378875Y668437I-2299J-2298D01*
G01X378680Y668444D01*
X378247Y668877D01*
G02X378100Y669230I353J354D01*
G01Y672905D01*
G03X375065Y675014I-2250J0D01*
G01X375025Y675000D01*
X374930Y674982D01*
G02X374483Y675120I-93J491D01*
G37*
G36*
G01X61963Y1017508D02*
X62259Y1017607D01*
X62530Y1017526D01*
X62586Y1017492D01*
G03X62872Y1017349I990J1623D01*
G03X62956Y1017318I700J1768D01*
G03X64662Y1017554I621J1797D01*
G01X64791Y1017643D01*
X65874D01*
X66908Y1016609D01*
Y1001278D01*
X64642Y999012D01*
X63285Y997654D01*
X61258Y995627D01*
Y887643D01*
G02X59569Y886918I-1000J0D01*
G03Y877636I-4411J-4641D01*
G02X61258Y876911I689J-725D01*
G01Y874045D01*
X69055Y866248D01*
X69075Y866074D01*
G03X71862Y864777I1790J204D01*
G01X71987Y864860D01*
X72138D01*
G02X72638Y864360I0J-500D01*
G01Y863892D01*
X71915Y863169D01*
X71482Y862735D01*
X70835Y862088D01*
X70661Y862068D01*
G03X72655Y860074I204J-1790D01*
G01X72675Y860248D01*
X73596Y861169D01*
X74213Y861785D01*
X75242Y862814D01*
Y927535D01*
X83620Y935913D01*
G02X85192Y935648I686J-727D01*
G01Y933129D01*
X89878Y928443D01*
Y928068D01*
X89849Y928028D01*
G03X89992Y925705I1445J-1077D01*
G01Y919995D01*
X84142Y914144D01*
Y873728D01*
X85718Y872151D01*
Y841270D01*
X81240Y836792D01*
X50100D01*
X39332Y826024D01*
G02X38625I-353J354D01*
G01X38279Y826371D01*
G02X38132Y826724I353J354D01*
G01Y831224D01*
X35141Y834216D01*
G02X35110Y835598I707J707D01*
G03X30860Y837982I-1847J1688D01*
G02X29192Y837553I-961J278D01*
G01X27536Y839209D01*
G02X27473Y839839I354J354D01*
G03X23888Y839222I-2084J1384D01*
G01X24088Y839072D01*
Y838977D01*
X25549Y837515D01*
G02X24998Y835820I-707J-707D01*
G03X27860Y832958I391J-2471D01*
G02X29555Y833509I988J-156D01*
G01X30927Y832138D01*
X31060D01*
X31316Y831963D01*
X31468Y831567D01*
G02X31378Y831058I-466J-180D01*
G03X31251Y827924I1885J-1646D01*
G02X30447Y826330I-804J-594D01*
G01X30335D01*
X24088Y820082D01*
Y820003D01*
G02X23888Y819603I-500J0D01*
G03X27328Y816019I1501J-2002D01*
G01X27396Y816102D01*
X27791Y816300D01*
X30198D01*
G02X31064Y814858I-31J-1000D01*
G03Y812470I2199J-1194D01*
G02X30211Y811028I-897J-442D01*
G01X27790D01*
X27396Y811226D01*
X27328Y811309D01*
G03Y808145I-1939J-1582D01*
G01X27396Y808228D01*
X27790Y808426D01*
X30211D01*
G02X31064Y806984I-44J-1000D01*
G03X30786Y805436I2199J-1194D01*
G01X30803Y805319D01*
X30728Y805096D01*
X28786Y803154D01*
X27791D01*
X27396Y803352D01*
X27328Y803435D01*
G03X23888Y799851I-1939J-1582D01*
G02X24088Y799451I-300J-400D01*
G01Y798824D01*
X31137Y791775D01*
X31181Y791439D01*
X31096Y791292D01*
G03X35726Y790479I2167J-1251D01*
G02X36711Y791654I985J175D01*
G01X37682D01*
X67274Y762063D01*
G02X67420Y761710I-354J-353D01*
G01Y558957D01*
X74580Y551797D01*
Y527520D01*
X68807Y521747D01*
G02X67406Y521734I-707J707D01*
G03X63626Y522140I-2152J-2234D01*
G02X62101Y522992I-525J851D01*
G01Y524376D01*
X59936Y526541D01*
G02X60643Y528248I707J707D01*
G01X62243D01*
X62477Y528111D01*
X62543Y527992D01*
G03X68109Y530714I2711J1508D01*
G02X69029Y532106I920J392D01*
G01X69809D01*
X73082Y535379D01*
Y542129D01*
X67839Y547373D01*
X67799Y547719D01*
X67891Y547866D01*
G03X63575Y552108I-2637J1634D01*
G02X62814Y552627I-271J421D01*
G03X62838Y552873I-1227J244D01*
G01Y559320D01*
X59708Y562451D01*
Y576793D01*
X55195Y581306D01*
Y672683D01*
G02X56498Y673637I1000J1D01*
G03X56820Y673551I624J1691D01*
G03X57002Y673529I307J1776D01*
G02X57934Y672531I-68J-997D01*
G01Y672016D01*
X57825Y671879D01*
G03X59231Y668956I1411J-1121D01*
G03X60538Y672004I5J1802D01*
G01Y737296D01*
X44913Y752921D01*
Y755451D01*
X36674Y763690D01*
X28966D01*
X27245Y765411D01*
X13327D01*
X10984Y763068D01*
X6966D01*
X6040Y763994D01*
Y770849D01*
G02X7221Y771832I1000J0D01*
G03Y776754I452J2461D01*
G02X6040Y777737I-181J983D01*
G01Y778723D01*
G02X7221Y779706I1000J0D01*
G03Y784628I452J2461D01*
G02X6040Y785611I-181J983D01*
G01Y786597D01*
G02X7221Y787580I1000J0D01*
G03Y792502I452J2461D01*
G02X6040Y793485I-181J983D01*
G01Y794471D01*
G02X7221Y795454I1000J0D01*
G03Y800376I452J2461D01*
G02X6040Y801359I-181J983D01*
G01Y802346D01*
G02X7221Y803329I1000J0D01*
G03Y808251I452J2461D01*
G02X6040Y809234I-181J983D01*
G01Y810220D01*
G02X7221Y811203I1000J0D01*
G03Y816125I452J2461D01*
G02X6040Y817108I-181J983D01*
G01Y818094D01*
G02X7221Y819077I1000J0D01*
G03Y823999I452J2461D01*
G02X6040Y824982I-181J983D01*
G01Y825968D01*
G02X7221Y826951I1000J0D01*
G03Y831873I452J2461D01*
G02X6040Y832856I-181J983D01*
G01Y833842D01*
G02X7221Y834825I1000J0D01*
G03Y839747I452J2461D01*
G02X6040Y840730I-181J983D01*
G01Y841716D01*
G02X7221Y842699I1000J0D01*
G03Y847621I452J2461D01*
G02X6040Y848604I-181J983D01*
G01Y857464D01*
G02X7221Y858447I1000J0D01*
G03Y863369I452J2461D01*
G02X6040Y864352I-181J983D01*
G01Y865338D01*
G02X7221Y866321I1000J0D01*
G03Y871243I452J2461D01*
G02X6040Y872226I-181J983D01*
G01Y873212D01*
G02X7221Y874195I1000J0D01*
G03Y879117I452J2461D01*
G02X6040Y880100I-181J983D01*
G01Y888960D01*
G02X7221Y889943I1000J0D01*
G03Y894865I452J2461D01*
G02X6040Y895848I-181J983D01*
G01Y896834D01*
G02X7221Y897817I1000J0D01*
G03Y902739I452J2461D01*
G02X6040Y903722I-181J983D01*
G01Y904708D01*
G02X7221Y905691I1000J0D01*
G03Y910613I452J2461D01*
G02X6040Y911596I-181J983D01*
G01Y912582D01*
G02X7221Y913565I1000J0D01*
G03Y918487I452J2461D01*
G02X6040Y919470I-181J983D01*
G01Y928330D01*
G02X7221Y929313I1000J0D01*
G03Y934235I452J2461D01*
G02X6040Y935218I-181J983D01*
G01Y936204D01*
G02X7221Y937187I1000J0D01*
G03Y942109I452J2461D01*
G02X6040Y943092I-181J983D01*
G01Y944078D01*
G02X7221Y945061I1000J0D01*
G03Y949983I452J2461D01*
G02X6040Y950966I-181J983D01*
G01Y951952D01*
G02X7221Y952935I1000J0D01*
G03Y957857I452J2461D01*
G02X6040Y958840I-181J983D01*
G01Y967700D01*
G02X7221Y968683I1000J0D01*
G03Y973605I452J2461D01*
G02X6040Y974588I-181J983D01*
G01Y975574D01*
G02X7221Y976557I1000J0D01*
G03Y981479I452J2461D01*
G02X6040Y982462I-181J983D01*
G01Y991322D01*
G02X7221Y992305I1000J0D01*
G03Y997227I452J2461D01*
G02X6040Y998210I-181J983D01*
G01Y999196D01*
G02X7221Y1000179I1000J0D01*
G03Y1005101I452J2461D01*
G02X6040Y1006084I-181J983D01*
G01Y1007070D01*
G02X7221Y1008053I1000J0D01*
G03Y1012975I452J2461D01*
G02X6040Y1013958I-181J983D01*
G01Y1022818D01*
G02X7221Y1023801I1000J0D01*
G03Y1028723I452J2461D01*
G02X6040Y1029706I-181J983D01*
G01Y1058248D01*
G02X7222Y1059232I1000J1D01*
G03Y1064152I455J2460D01*
G02X6040Y1065136I-182J983D01*
G01Y1073996D01*
G02X7222Y1074980I1000J1D01*
G03Y1079900I455J2460D01*
G02X6040Y1080884I-182J983D01*
G01Y1081870D01*
G02X7222Y1082854I1000J1D01*
G03Y1087774I455J2460D01*
G02X6040Y1088758I-182J983D01*
G01Y1089744D01*
G02X7222Y1090728I1000J1D01*
G03Y1095648I455J2460D01*
G02X6040Y1096632I-182J983D01*
G01Y1097618D01*
G02X7222Y1098602I1000J1D01*
G03Y1103522I455J2460D01*
G02X6040Y1104506I-182J983D01*
G01Y1113366D01*
G02X7222Y1114350I1000J1D01*
G03Y1119270I455J2460D01*
G02X6040Y1120254I-182J983D01*
G01Y1121240D01*
G02X7222Y1122224I1000J1D01*
G03Y1127144I455J2460D01*
G02X6040Y1128128I-182J983D01*
G01Y1129114D01*
G02X7222Y1130098I1000J1D01*
G03Y1135018I455J2460D01*
G02X6040Y1136002I-182J983D01*
G01Y1136988D01*
G02X7222Y1137972I1000J1D01*
G03Y1142892I455J2460D01*
G02X6040Y1143876I-182J983D01*
G01Y1152736D01*
G02X7222Y1153720I1000J1D01*
G03Y1158640I455J2460D01*
G02X6040Y1159624I-182J983D01*
G01Y1160611D01*
G02X7222Y1161595I1000J1D01*
G03Y1166515I455J2460D01*
G02X6040Y1167499I-182J983D01*
G01Y1168485D01*
G02X7222Y1169469I1000J1D01*
G03Y1174389I455J2460D01*
G02X6040Y1175373I-182J983D01*
G01Y1176359D01*
G02X7222Y1177343I1000J1D01*
G03Y1182263I455J2460D01*
G02X6040Y1183247I-182J983D01*
G01Y1192107D01*
G02X7222Y1193091I1000J1D01*
G03Y1198011I455J2460D01*
G02X6040Y1198995I-182J983D01*
G01Y1199981D01*
G02X7222Y1200965I1000J1D01*
G03Y1205885I455J2460D01*
G02X6040Y1206869I-182J983D01*
G01Y1207855D01*
G02X7222Y1208839I1000J1D01*
G03Y1213759I455J2460D01*
G02X6040Y1214743I-182J983D01*
G01Y1215729D01*
G02X7222Y1216713I1000J1D01*
G03Y1221633I455J2460D01*
G02X6040Y1222617I-182J983D01*
G01Y1231477D01*
G02X7222Y1232461I1000J1D01*
G03Y1237381I455J2460D01*
G02X6040Y1238365I-182J983D01*
G01Y1239351D01*
G02X7222Y1240335I1000J1D01*
G03Y1245255I455J2460D01*
G02X6040Y1246239I-182J983D01*
G01Y1247225D01*
G02X7222Y1248209I1000J1D01*
G03Y1253129I455J2460D01*
G02X6040Y1254113I-182J983D01*
G01Y1255099D01*
G02X7222Y1256083I1000J1D01*
G03Y1261003I455J2460D01*
G02X6040Y1261987I-182J983D01*
G01Y1270847D01*
G02X7222Y1271831I1000J1D01*
G03X8585Y1271960I455J2460D01*
G03X9616Y1272709I-907J2332D01*
G01X9684Y1272792D01*
X10078Y1272990D01*
X12499D01*
G02X13352Y1271548I-44J-1000D01*
G03X17793Y1269243I2199J-1194D01*
G02X19363Y1269502I884J-468D01*
G01X20540Y1268325D01*
X23467Y1265399D01*
X24249Y1264616D01*
X27417D01*
X27852Y1264181D01*
X30122Y1261912D01*
X30732D01*
G02X31432Y1260244I-44J-1000D01*
G03X35102I1835J-1701D01*
G02X35802Y1261912I744J668D01*
G01X36595D01*
X38529Y1263845D01*
X41986Y1267302D01*
Y1278165D01*
X42660Y1278840D01*
X42953Y1279133D01*
G02X43661I354J-353D01*
G02X43801Y1278701I-354J-353D01*
G03X46075Y1280153I1780J-281D01*
G02X45642Y1281822I274J962D01*
G01X45774Y1281954D01*
X45900Y1281989D01*
G03X46403Y1285230I-487J1735D01*
G01X46297Y1285299D01*
X46178Y1285521D01*
Y1287266D01*
G02X46367Y1287657I500J0D01*
G03Y1290477I-1123J1410D01*
G02X46178Y1290868I311J391D01*
G01Y1292500D01*
X46280Y1292708D01*
X46372Y1292779D01*
G03Y1295627I-1105J1424D01*
G01X46280Y1295698D01*
X46178Y1295906D01*
Y1297939D01*
X46290Y1298155D01*
X46390Y1298225D01*
G03Y1301169I-1040J1472D01*
G01X46290Y1301239D01*
X46178Y1301455D01*
Y1303986D01*
G02X46367Y1304377I500J0D01*
G03Y1307197I-1123J1410D01*
G02X46178Y1307588I311J391D01*
G01Y1309181D01*
X46281Y1309390D01*
X46375Y1309461D01*
G03Y1312325I-1094J1432D01*
G01X46281Y1312396D01*
X46178Y1312605D01*
Y1313080D01*
G02X47084Y1314044I1000J-32D01*
G03X47200Y1317632I-103J1799D01*
G03X46744Y1317629I-216J-1789D01*
G01X46711Y1317625D01*
X46678D01*
G02X46178Y1318125I0J500D01*
G01Y1318561D01*
G02X46678Y1319061I500J0D01*
G01X46711D01*
X46744Y1319057D01*
G03Y1322629I236J1786D01*
G01X46711Y1322625D01*
X46678D01*
G02X46178Y1323125I0J500D01*
G01Y1323561D01*
G02X46678Y1324061I500J0D01*
G01X46711D01*
X46744Y1324057D01*
G03Y1327629I236J1786D01*
G01X46711Y1327625D01*
X46678D01*
G02X46178Y1328125I0J500D01*
G01Y1328561D01*
G02X46678Y1329061I500J0D01*
G01X46711D01*
X46744Y1329057D01*
G03Y1332629I236J1786D01*
G01X46711Y1332625D01*
X46678D01*
G02X46178Y1333125I0J500D01*
G01Y1333561D01*
G02X46678Y1334061I500J0D01*
G01X46711D01*
X46744Y1334057D01*
G03Y1337629I236J1786D01*
G01X46711Y1337625D01*
X46678D01*
G02X46178Y1338125I0J500D01*
G01Y1338561D01*
G02X46678Y1339061I500J0D01*
G01X46711D01*
X46744Y1339057D01*
G03Y1342629I236J1786D01*
G01X46711Y1342625D01*
X46678D01*
G02X46178Y1343125I0J500D01*
G01Y1343561D01*
G02X46678Y1344061I500J0D01*
G01X46711D01*
X46744Y1344057D01*
G03X47066Y1344043I239J1786D01*
G03X48568Y1346696I-85J1800D01*
G01Y1346697D01*
G02X48655Y1347287I440J236D01*
G01X55285Y1353917D01*
Y1463872D01*
X82928Y1491515D01*
G02X84606Y1490824I678J-736D01*
G01Y1419239D01*
X82901Y1417534D01*
X77442Y1412076D01*
Y1269000D01*
X94538Y1251905D01*
G02X94678Y1251558I-360J-347D01*
G01Y1145104D01*
G02X94532Y1144751I-500J0D01*
G01X73912Y1124132D01*
Y1106889D01*
X58914Y1091890D01*
Y1019026D01*
G03X61792Y1017395I1901J0D01*
G03X61904Y1017467I-971J1634D01*
G01X61963Y1017508D01*
G37*
G36*
G01X65354Y795260D02*
G02I0J19700D01*
G37*
G36*
G01Y1495260D02*
G02I0J19700D01*
G37*
G36*
G01X113402Y456560D02*
Y459393D01*
G02X115109Y460100I1000J0D01*
G01X116033Y459176D01*
X146527D01*
X150818Y454885D01*
G02X150111Y453177I-707J-708D01*
G01X116784D01*
X113402Y456560D01*
G37*
%LPC*%
G75*
G36*
G01X170004Y552205D02*
G02X156767Y552182I-6619J0D01*
G02X169983Y552726I6618J30D01*
G02X169986Y552689I-6594J-553D01*
G02X170004Y552205I-6600J-488D01*
G37*
G36*
G01X169982Y1952727D02*
G02X170003Y1952205I-6597J-527D01*
G02X156766I-6618J0D01*
G02X169982Y1952727I6618J0D01*
G37*
G36*
G01X316910Y1923081D02*
G03X315710I-600J-800D01*
G02Y1925485I-900J1202D01*
G03X316910I600J800D01*
G02Y1923081I900J-1202D01*
G37*
G36*
G01X294854Y1922901D02*
G03X293654I-600J-800D01*
G02Y1925305I-900J1202D01*
G03X294854I600J800D01*
G02Y1922901I900J-1202D01*
G37*
G36*
G01X316910Y1916126D02*
G03X315710I-600J-800D01*
G02Y1918530I-900J1202D01*
G03X316910I600J800D01*
G02Y1916126I900J-1202D01*
G37*
G36*
G01X294854Y1915946D02*
G03X293654I-600J-800D01*
G02Y1918350I-900J1202D01*
G03X294854I600J800D01*
G02Y1915946I900J-1202D01*
G37*
G36*
G01X316910Y1909210D02*
G03X315710I-600J-800D01*
G02Y1911614I-900J1202D01*
G03X316910I600J800D01*
G02Y1909210I900J-1202D01*
G37*
G36*
G01X294854Y1909030D02*
G03X293654I-600J-800D01*
G02Y1911434I-900J1202D01*
G03X294854I600J800D01*
G02Y1909030I900J-1202D01*
G37*
G36*
G01X269137Y1838891D02*
G03X267937I-600J-800D01*
G02Y1841295I-900J1202D01*
G03X269137I600J800D01*
G02Y1838891I900J-1202D01*
G37*
G36*
G01X260559Y1838888D02*
G03X259359I-600J-800D01*
G02Y1841292I-900J1202D01*
G03X260559I600J800D01*
G02Y1838888I900J-1202D01*
G37*
G36*
G01X252388D02*
G03X251188I-600J-800D01*
G02Y1841292I-900J1202D01*
G03X252388I600J800D01*
G02Y1838888I900J-1202D01*
G37*
G36*
G01X269137Y1831936D02*
G03X267937I-600J-800D01*
G02Y1834340I-900J1202D01*
G03X269137I600J800D01*
G02Y1831936I900J-1202D01*
G37*
G36*
G01X260559Y1831933D02*
G03X259359I-600J-800D01*
G02Y1834337I-900J1202D01*
G03X260559I600J800D01*
G02Y1831933I900J-1202D01*
G37*
G36*
G01X252388D02*
G03X251188I-600J-800D01*
G02Y1834337I-900J1202D01*
G03X252388I600J800D01*
G02Y1831933I900J-1202D01*
G37*
G36*
G01X269137Y1825020D02*
G03X267937I-600J-800D01*
G02Y1827424I-900J1202D01*
G03X269137I600J800D01*
G02Y1825020I900J-1202D01*
G37*
G36*
G01X260559Y1825017D02*
G03X259359I-600J-800D01*
G02Y1827421I-900J1202D01*
G03X260559I600J800D01*
G02Y1825017I900J-1202D01*
G37*
G36*
G01X252388D02*
G03X251188I-600J-800D01*
G02Y1827421I-900J1202D01*
G03X252388I600J800D01*
G02Y1825017I900J-1202D01*
G37*
G36*
G01X269496Y1817875D02*
G03X268296I-600J-800D01*
G02Y1820279I-900J1202D01*
G03X269496I600J800D01*
G02Y1817875I900J-1202D01*
G37*
G36*
G01X260739Y1817872D02*
G03X259539I-600J-800D01*
G02Y1820276I-900J1202D01*
G03X260739I600J800D01*
G02Y1817872I900J-1202D01*
G37*
G36*
G01X252568D02*
G03X251368I-600J-800D01*
G02Y1820276I-900J1202D01*
G03X252568I600J800D01*
G02Y1817872I900J-1202D01*
G37*
G36*
G01X269496Y1810920D02*
G03X268296I-600J-800D01*
G02Y1813324I-900J1202D01*
G03X269496I600J800D01*
G02Y1810920I900J-1202D01*
G37*
G36*
G01X260739Y1810917D02*
G03X259539I-600J-800D01*
G02Y1813321I-900J1202D01*
G03X260739I600J800D01*
G02Y1810917I900J-1202D01*
G37*
G36*
G01X252568D02*
G03X251368I-600J-800D01*
G02Y1813321I-900J1202D01*
G03X252568I600J800D01*
G02Y1810917I900J-1202D01*
G37*
G36*
G01X269496Y1804004D02*
G03X268296I-600J-800D01*
G02Y1806408I-900J1202D01*
G03X269496I600J800D01*
G02Y1804004I900J-1202D01*
G37*
G36*
G01X260739Y1804001D02*
G03X259539I-600J-800D01*
G02Y1806405I-900J1202D01*
G03X260739I600J800D01*
G02Y1804001I900J-1202D01*
G37*
G36*
G01X252568D02*
G03X251368I-600J-800D01*
G02Y1806405I-900J1202D01*
G03X252568I600J800D01*
G02Y1804001I900J-1202D01*
G37*
G36*
G01X264598Y1720938D02*
G03X263398I-600J-800D01*
G02Y1723342I-900J1202D01*
G03X264598I600J800D01*
G02Y1720938I900J-1202D01*
G37*
G36*
G01X253557D02*
G03X252357I-600J-800D01*
G02Y1723342I-900J1202D01*
G03X253557I600J800D01*
G02Y1720938I900J-1202D01*
G37*
G36*
G01X264859Y1713476D02*
G03X263659I-600J-800D01*
G02Y1715880I-900J1202D01*
G03X264859I600J800D01*
G02Y1713476I900J-1202D01*
G37*
G36*
G01X253818D02*
G03X252618I-600J-800D01*
G02Y1715880I-900J1202D01*
G03X253818I600J800D01*
G02Y1713476I900J-1202D01*
G37*
G36*
G01X264859Y1705748D02*
G03X263659I-600J-800D01*
G02Y1708152I-900J1202D01*
G03X264859I600J800D01*
G02Y1705748I900J-1202D01*
G37*
G36*
G01X253818D02*
G03X252618I-600J-800D01*
G02Y1708152I-900J1202D01*
G03X253818I600J800D01*
G02Y1705748I900J-1202D01*
G37*
G36*
G01X160592Y1702570D02*
G03X159392I-600J-800D01*
G02Y1704974I-900J1202D01*
G03X160592I600J800D01*
G02Y1702570I900J-1202D01*
G37*
G36*
G01X264859Y1696411D02*
G03X263659I-600J-800D01*
G02Y1698815I-900J1202D01*
G03X264859I600J800D01*
G02Y1696411I900J-1202D01*
G37*
G36*
G01X253818D02*
G03X252618I-600J-800D01*
G02Y1698815I-900J1202D01*
G03X253818I600J800D01*
G02Y1696411I900J-1202D01*
G37*
G36*
G01X160592Y1694131D02*
G03X159392I-600J-800D01*
G02Y1696535I-900J1202D01*
G03X160592I600J800D01*
G02Y1694131I900J-1202D01*
G37*
G36*
G01Y1686403D02*
G03X159392I-600J-800D01*
G02Y1688807I-900J1202D01*
G03X160592I600J800D01*
G02Y1686403I900J-1202D01*
G37*
G36*
G01X264859Y1685906D02*
G03X263659I-600J-800D01*
G02Y1688310I-900J1202D01*
G03X264859I600J800D01*
G02Y1685906I900J-1202D01*
G37*
G36*
G01X253818D02*
G03X252618I-600J-800D01*
G02Y1688310I-900J1202D01*
G03X253818I600J800D01*
G02Y1685906I900J-1202D01*
G37*
G36*
G01X160592Y1677066D02*
G03X159392I-600J-800D01*
G02Y1679470I-900J1202D01*
G03X160592I600J800D01*
G02Y1677066I900J-1202D01*
G37*
G36*
G01X264859Y1675391D02*
G03X263659I-600J-800D01*
G02Y1677795I-900J1202D01*
G03X264859I600J800D01*
G02Y1675391I900J-1202D01*
G37*
G36*
G01X253818D02*
G03X252618I-600J-800D01*
G02Y1677795I-900J1202D01*
G03X253818I600J800D01*
G02Y1675391I900J-1202D01*
G37*
G36*
G01X272442Y1667145D02*
G03X271242I-600J-800D01*
G02Y1669549I-900J1202D01*
G03X272442I600J800D01*
G02Y1667145I900J-1202D01*
G37*
G36*
G01X260664D02*
G03X259464I-600J-800D01*
G02Y1669549I-900J1202D01*
G03X260664I600J800D01*
G02Y1667145I900J-1202D01*
G37*
G36*
G01X160592Y1666561D02*
G03X159392I-600J-800D01*
G02Y1668965I-900J1202D01*
G03X160592I600J800D01*
G02Y1666561I900J-1202D01*
G37*
G36*
G01X272442Y1658706D02*
G03X271242I-600J-800D01*
G02Y1661110I-900J1202D01*
G03X272442I600J800D01*
G02Y1658706I900J-1202D01*
G37*
G36*
G01X260664D02*
G03X259464I-600J-800D01*
G02Y1661110I-900J1202D01*
G03X260664I600J800D01*
G02Y1658706I900J-1202D01*
G37*
G36*
G01X160592Y1656046D02*
G03X159392I-600J-800D01*
G02Y1658450I-900J1202D01*
G03X160592I600J800D01*
G02Y1656046I900J-1202D01*
G37*
G36*
G01X272442Y1650978D02*
G03X271242I-600J-800D01*
G02Y1653382I-900J1202D01*
G03X272442I600J800D01*
G02Y1650978I900J-1202D01*
G37*
G36*
G01X260664D02*
G03X259464I-600J-800D01*
G02Y1653382I-900J1202D01*
G03X260664I600J800D01*
G02Y1650978I900J-1202D01*
G37*
G36*
G01X272442Y1641641D02*
G03X271242I-600J-800D01*
G02Y1644045I-900J1202D01*
G03X272442I600J800D01*
G02Y1641641I900J-1202D01*
G37*
G36*
G01X260664D02*
G03X259464I-600J-800D01*
G02Y1644045I-900J1202D01*
G03X260664I600J800D01*
G02Y1641641I900J-1202D01*
G37*
G36*
G01X272442Y1631136D02*
G03X271242I-600J-800D01*
G02Y1633540I-900J1202D01*
G03X272442I600J800D01*
G02Y1631136I900J-1202D01*
G37*
G36*
G01X260664D02*
G03X259464I-600J-800D01*
G02Y1633540I-900J1202D01*
G03X260664I600J800D01*
G02Y1631136I900J-1202D01*
G37*
G36*
G01X272442Y1620621D02*
G03X271242I-600J-800D01*
G02Y1623025I-900J1202D01*
G03X272442I600J800D01*
G02Y1620621I900J-1202D01*
G37*
G36*
G01X260664D02*
G03X259464I-600J-800D01*
G02Y1623025I-900J1202D01*
G03X260664I600J800D01*
G02Y1620621I900J-1202D01*
G37*
G36*
G01X169982Y1602727D02*
G02X170003Y1602205I-6597J-527D01*
G02X156766I-6618J0D01*
G02X169982Y1602727I6618J0D01*
G37*
G36*
G01X285095Y1546988D02*
G03X283895I-600J-800D01*
G02Y1549392I-900J1202D01*
G03X285095I600J800D01*
G02Y1546988I900J-1202D01*
G37*
G36*
G01X263039Y1546808D02*
G03X261839I-600J-800D01*
G02Y1549212I-900J1202D01*
G03X263039I600J800D01*
G02Y1546808I900J-1202D01*
G37*
G36*
G01X285095Y1540033D02*
G03X283895I-600J-800D01*
G02Y1542437I-900J1202D01*
G03X285095I600J800D01*
G02Y1540033I900J-1202D01*
G37*
G36*
G01X263039Y1539853D02*
G03X261839I-600J-800D01*
G02Y1542257I-900J1202D01*
G03X263039I600J800D01*
G02Y1539853I900J-1202D01*
G37*
G36*
G01X285095Y1533117D02*
G03X283895I-600J-800D01*
G02Y1535521I-900J1202D01*
G03X285095I600J800D01*
G02Y1533117I900J-1202D01*
G37*
G36*
G01X263039Y1532937D02*
G03X261839I-600J-800D01*
G02Y1535341I-900J1202D01*
G03X263039I600J800D01*
G02Y1532937I900J-1202D01*
G37*
G36*
G01X311564Y1492771D02*
G03X310364I-600J-800D01*
G02Y1495175I-900J1202D01*
G03X311564I600J800D01*
G02Y1492771I900J-1202D01*
G37*
G36*
G01X302986Y1492768D02*
G03X301786I-600J-800D01*
G02Y1495172I-900J1202D01*
G03X302986I600J800D01*
G02Y1492768I900J-1202D01*
G37*
G36*
G01X294815D02*
G03X293615I-600J-800D01*
G02Y1495172I-900J1202D01*
G03X294815I600J800D01*
G02Y1492768I900J-1202D01*
G37*
G36*
G01X311564Y1485816D02*
G03X310364I-600J-800D01*
G02Y1488220I-900J1202D01*
G03X311564I600J800D01*
G02Y1485816I900J-1202D01*
G37*
G36*
G01X302986Y1485813D02*
G03X301786I-600J-800D01*
G02Y1488217I-900J1202D01*
G03X302986I600J800D01*
G02Y1485813I900J-1202D01*
G37*
G36*
G01X294815D02*
G03X293615I-600J-800D01*
G02Y1488217I-900J1202D01*
G03X294815I600J800D01*
G02Y1485813I900J-1202D01*
G37*
G36*
G01X311564Y1478900D02*
G03X310364I-600J-800D01*
G02Y1481304I-900J1202D01*
G03X311564I600J800D01*
G02Y1478900I900J-1202D01*
G37*
G36*
G01X302986Y1478897D02*
G03X301786I-600J-800D01*
G02Y1481301I-900J1202D01*
G03X302986I600J800D01*
G02Y1478897I900J-1202D01*
G37*
G36*
G01X294815D02*
G03X293615I-600J-800D01*
G02Y1481301I-900J1202D01*
G03X294815I600J800D01*
G02Y1478897I900J-1202D01*
G37*
G36*
G01X311923Y1471755D02*
G03X310723I-600J-800D01*
G02Y1474159I-900J1202D01*
G03X311923I600J800D01*
G02Y1471755I900J-1202D01*
G37*
G36*
G01X303166Y1471752D02*
G03X301966I-600J-800D01*
G02Y1474156I-900J1202D01*
G03X303166I600J800D01*
G02Y1471752I900J-1202D01*
G37*
G36*
G01X294995D02*
G03X293795I-600J-800D01*
G02Y1474156I-900J1202D01*
G03X294995I600J800D01*
G02Y1471752I900J-1202D01*
G37*
G36*
G01X311923Y1464800D02*
G03X310723I-600J-800D01*
G02Y1467204I-900J1202D01*
G03X311923I600J800D01*
G02Y1464800I900J-1202D01*
G37*
G36*
G01X303166Y1464797D02*
G03X301966I-600J-800D01*
G02Y1467201I-900J1202D01*
G03X303166I600J800D01*
G02Y1464797I900J-1202D01*
G37*
G36*
G01X294995D02*
G03X293795I-600J-800D01*
G02Y1467201I-900J1202D01*
G03X294995I600J800D01*
G02Y1464797I900J-1202D01*
G37*
G36*
G01X311923Y1457884D02*
G03X310723I-600J-800D01*
G02Y1460288I-900J1202D01*
G03X311923I600J800D01*
G02Y1457884I900J-1202D01*
G37*
G36*
G01X303166Y1457881D02*
G03X301966I-600J-800D01*
G02Y1460285I-900J1202D01*
G03X303166I600J800D01*
G02Y1457881I900J-1202D01*
G37*
G36*
G01X294995D02*
G03X293795I-600J-800D01*
G02Y1460285I-900J1202D01*
G03X294995I600J800D01*
G02Y1457881I900J-1202D01*
G37*
G36*
G01X157849Y1353055D02*
G03X156649I-600J-800D01*
G02Y1355459I-900J1202D01*
G03X157849I600J800D01*
G02Y1353055I900J-1202D01*
G37*
G36*
G01Y1344616D02*
G03X156649I-600J-800D01*
G02Y1347020I-900J1202D01*
G03X157849I600J800D01*
G02Y1344616I900J-1202D01*
G37*
G36*
G01X245025Y1338638D02*
G03X243825I-600J-800D01*
G02Y1341042I-900J1202D01*
G03X245025I600J800D01*
G02Y1338638I900J-1202D01*
G37*
G36*
G01X237529D02*
G03X236329I-600J-800D01*
G02Y1341042I-900J1202D01*
G03X237529I600J800D01*
G02Y1338638I900J-1202D01*
G37*
G36*
G01X228706D02*
G03X227506I-600J-800D01*
G02Y1341042I-900J1202D01*
G03X228706I600J800D01*
G02Y1338638I900J-1202D01*
G37*
G36*
G01X221278D02*
G03X220078I-600J-800D01*
G02Y1341042I-900J1202D01*
G03X221278I600J800D01*
G02Y1338638I900J-1202D01*
G37*
G36*
G01X157849Y1336888D02*
G03X156649I-600J-800D01*
G02Y1339292I-900J1202D01*
G03X157849I600J800D01*
G02Y1336888I900J-1202D01*
G37*
G36*
G01X245025Y1331119D02*
G03X243825I-600J-800D01*
G02Y1333523I-900J1202D01*
G03X245025I600J800D01*
G02Y1331119I900J-1202D01*
G37*
G36*
G01X237529D02*
G03X236329I-600J-800D01*
G02Y1333523I-900J1202D01*
G03X237529I600J800D01*
G02Y1331119I900J-1202D01*
G37*
G36*
G01X228706D02*
G03X227506I-600J-800D01*
G02Y1333523I-900J1202D01*
G03X228706I600J800D01*
G02Y1331119I900J-1202D01*
G37*
G36*
G01X221278D02*
G03X220078I-600J-800D01*
G02Y1333523I-900J1202D01*
G03X221278I600J800D01*
G02Y1331119I900J-1202D01*
G37*
G36*
G01X157849Y1327551D02*
G03X156649I-600J-800D01*
G02Y1329955I-900J1202D01*
G03X157849I600J800D01*
G02Y1327551I900J-1202D01*
G37*
G36*
G01X245025Y1323083D02*
G03X243825I-600J-800D01*
G02Y1325487I-900J1202D01*
G03X245025I600J800D01*
G02Y1323083I900J-1202D01*
G37*
G36*
G01X237529D02*
G03X236329I-600J-800D01*
G02Y1325487I-900J1202D01*
G03X237529I600J800D01*
G02Y1323083I900J-1202D01*
G37*
G36*
G01X228706D02*
G03X227506I-600J-800D01*
G02Y1325487I-900J1202D01*
G03X228706I600J800D01*
G02Y1323083I900J-1202D01*
G37*
G36*
G01X221278D02*
G03X220078I-600J-800D01*
G02Y1325487I-900J1202D01*
G03X221278I600J800D01*
G02Y1323083I900J-1202D01*
G37*
G36*
G01X269722Y1317752D02*
G03X268522I-600J-800D01*
G02Y1320156I-900J1202D01*
G03X269722I600J800D01*
G02Y1317752I900J-1202D01*
G37*
G36*
G01X258681D02*
G03X257481I-600J-800D01*
G02Y1320156I-900J1202D01*
G03X258681I600J800D01*
G02Y1317752I900J-1202D01*
G37*
G36*
G01X157849Y1317046D02*
G03X156649I-600J-800D01*
G02Y1319450I-900J1202D01*
G03X157849I600J800D01*
G02Y1317046I900J-1202D01*
G37*
G36*
G01X245025Y1315640D02*
G03X243825I-600J-800D01*
G02Y1318044I-900J1202D01*
G03X245025I600J800D01*
G02Y1315640I900J-1202D01*
G37*
G36*
G01X237529D02*
G03X236329I-600J-800D01*
G02Y1318044I-900J1202D01*
G03X237529I600J800D01*
G02Y1315640I900J-1202D01*
G37*
G36*
G01X228706D02*
G03X227506I-600J-800D01*
G02Y1318044I-900J1202D01*
G03X228706I600J800D01*
G02Y1315640I900J-1202D01*
G37*
G36*
G01X221278D02*
G03X220078I-600J-800D01*
G02Y1318044I-900J1202D01*
G03X221278I600J800D01*
G02Y1315640I900J-1202D01*
G37*
G36*
G01X269722Y1309313D02*
G03X268522I-600J-800D01*
G02Y1311717I-900J1202D01*
G03X269722I600J800D01*
G02Y1309313I900J-1202D01*
G37*
G36*
G01X258681D02*
G03X257481I-600J-800D01*
G02Y1311717I-900J1202D01*
G03X258681I600J800D01*
G02Y1309313I900J-1202D01*
G37*
G36*
G01X245196Y1307722D02*
G03X243996I-600J-800D01*
G02Y1310126I-900J1202D01*
G03X245196I600J800D01*
G02Y1307722I900J-1202D01*
G37*
G36*
G01X237700D02*
G03X236500I-600J-800D01*
G02Y1310126I-900J1202D01*
G03X237700I600J800D01*
G02Y1307722I900J-1202D01*
G37*
G36*
G01X228877D02*
G03X227677I-600J-800D01*
G02Y1310126I-900J1202D01*
G03X228877I600J800D01*
G02Y1307722I900J-1202D01*
G37*
G36*
G01X221449D02*
G03X220249I-600J-800D01*
G02Y1310126I-900J1202D01*
G03X221449I600J800D01*
G02Y1307722I900J-1202D01*
G37*
G36*
G01X157849Y1306531D02*
G03X156649I-600J-800D01*
G02Y1308935I-900J1202D01*
G03X157849I600J800D01*
G02Y1306531I900J-1202D01*
G37*
G36*
G01X269722Y1301585D02*
G03X268522I-600J-800D01*
G02Y1303989I-900J1202D01*
G03X269722I600J800D01*
G02Y1301585I900J-1202D01*
G37*
G36*
G01X258681D02*
G03X257481I-600J-800D01*
G02Y1303989I-900J1202D01*
G03X258681I600J800D01*
G02Y1301585I900J-1202D01*
G37*
G36*
G01X245061Y1300773D02*
G03X243861I-600J-800D01*
G02Y1303177I-900J1202D01*
G03X245061I600J800D01*
G02Y1300773I900J-1202D01*
G37*
G36*
G01X237565D02*
G03X236365I-600J-800D01*
G02Y1303177I-900J1202D01*
G03X237565I600J800D01*
G02Y1300773I900J-1202D01*
G37*
G36*
G01X228742D02*
G03X227542I-600J-800D01*
G02Y1303177I-900J1202D01*
G03X228742I600J800D01*
G02Y1300773I900J-1202D01*
G37*
G36*
G01X221314D02*
G03X220114I-600J-800D01*
G02Y1303177I-900J1202D01*
G03X221314I600J800D01*
G02Y1300773I900J-1202D01*
G37*
G36*
G01X245061Y1293289D02*
G03X243861I-600J-800D01*
G02Y1295693I-900J1202D01*
G03X245061I600J800D01*
G02Y1293289I900J-1202D01*
G37*
G36*
G01X237565D02*
G03X236365I-600J-800D01*
G02Y1295693I-900J1202D01*
G03X237565I600J800D01*
G02Y1293289I900J-1202D01*
G37*
G36*
G01X228742D02*
G03X227542I-600J-800D01*
G02Y1295693I-900J1202D01*
G03X228742I600J800D01*
G02Y1293289I900J-1202D01*
G37*
G36*
G01X221314D02*
G03X220114I-600J-800D01*
G02Y1295693I-900J1202D01*
G03X221314I600J800D01*
G02Y1293289I900J-1202D01*
G37*
G36*
G01X269722Y1292248D02*
G03X268522I-600J-800D01*
G02Y1294652I-900J1202D01*
G03X269722I600J800D01*
G02Y1292248I900J-1202D01*
G37*
G36*
G01X258681D02*
G03X257481I-600J-800D01*
G02Y1294652I-900J1202D01*
G03X258681I600J800D01*
G02Y1292248I900J-1202D01*
G37*
G36*
G01X228742Y1286070D02*
G03X227542I-600J-800D01*
G02Y1288474I-900J1202D01*
G03X228742I600J800D01*
G02Y1286070I900J-1202D01*
G37*
G36*
G01X221314D02*
G03X220114I-600J-800D01*
G02Y1288474I-900J1202D01*
G03X221314I600J800D01*
G02Y1286070I900J-1202D01*
G37*
G36*
G01X269722Y1281743D02*
G03X268522I-600J-800D01*
G02Y1284147I-900J1202D01*
G03X269722I600J800D01*
G02Y1281743I900J-1202D01*
G37*
G36*
G01X258681D02*
G03X257481I-600J-800D01*
G02Y1284147I-900J1202D01*
G03X258681I600J800D01*
G02Y1281743I900J-1202D01*
G37*
G36*
G01X269722Y1271228D02*
G03X268522I-600J-800D01*
G02Y1273632I-900J1202D01*
G03X269722I600J800D01*
G02Y1271228I900J-1202D01*
G37*
G36*
G01X258681D02*
G03X257481I-600J-800D01*
G02Y1273632I-900J1202D01*
G03X258681I600J800D01*
G02Y1271228I900J-1202D01*
G37*
G36*
G01X169982Y1252727D02*
G02X170003Y1252205I-6597J-527D01*
G02X156766I-6618J0D01*
G02X169982Y1252727I6618J0D01*
G37*
G36*
G01X311259Y1199491D02*
G03X310059I-600J-800D01*
G02Y1201895I-900J1202D01*
G03X311259I600J800D01*
G02Y1199491I900J-1202D01*
G37*
G36*
G01X302791D02*
G03X301591I-600J-800D01*
G02Y1201895I-900J1202D01*
G03X302791I600J800D01*
G02Y1199491I900J-1202D01*
G37*
G36*
G01X320036Y1199490D02*
G03X318836I-600J-800D01*
G02Y1201894I-900J1202D01*
G03X320036I600J800D01*
G02Y1199490I900J-1202D01*
G37*
G36*
G01X286282Y1199420D02*
G03X285082I-600J-800D01*
G02Y1201824I-900J1202D01*
G03X286282I600J800D01*
G02Y1199420I900J-1202D01*
G37*
G36*
G01X294821Y1199277D02*
G03X293621I-600J-800D01*
G02Y1201681I-900J1202D01*
G03X294821I600J800D01*
G02Y1199277I900J-1202D01*
G37*
G36*
G01X311259Y1191052D02*
G03X310059I-600J-800D01*
G02Y1193456I-900J1202D01*
G03X311259I600J800D01*
G02Y1191052I900J-1202D01*
G37*
G36*
G01X302791D02*
G03X301591I-600J-800D01*
G02Y1193456I-900J1202D01*
G03X302791I600J800D01*
G02Y1191052I900J-1202D01*
G37*
G36*
G01X320036Y1191051D02*
G03X318836I-600J-800D01*
G02Y1193455I-900J1202D01*
G03X320036I600J800D01*
G02Y1191051I900J-1202D01*
G37*
G36*
G01X286282Y1190981D02*
G03X285082I-600J-800D01*
G02Y1193385I-900J1202D01*
G03X286282I600J800D01*
G02Y1190981I900J-1202D01*
G37*
G36*
G01X294821Y1190838D02*
G03X293621I-600J-800D01*
G02Y1193242I-900J1202D01*
G03X294821I600J800D01*
G02Y1190838I900J-1202D01*
G37*
G36*
G01X311259Y1183324D02*
G03X310059I-600J-800D01*
G02Y1185728I-900J1202D01*
G03X311259I600J800D01*
G02Y1183324I900J-1202D01*
G37*
G36*
G01X302791D02*
G03X301591I-600J-800D01*
G02Y1185728I-900J1202D01*
G03X302791I600J800D01*
G02Y1183324I900J-1202D01*
G37*
G36*
G01X320036Y1183323D02*
G03X318836I-600J-800D01*
G02Y1185727I-900J1202D01*
G03X320036I600J800D01*
G02Y1183323I900J-1202D01*
G37*
G36*
G01X286282Y1183253D02*
G03X285082I-600J-800D01*
G02Y1185657I-900J1202D01*
G03X286282I600J800D01*
G02Y1183253I900J-1202D01*
G37*
G36*
G01X294821Y1183110D02*
G03X293621I-600J-800D01*
G02Y1185514I-900J1202D01*
G03X294821I600J800D01*
G02Y1183110I900J-1202D01*
G37*
G36*
G01X244777Y1144718D02*
G03X243577I-600J-800D01*
G02Y1147122I-900J1202D01*
G03X244777I600J800D01*
G02Y1144718I900J-1202D01*
G37*
G36*
G01X234809D02*
G03X233609I-600J-800D01*
G02Y1147122I-900J1202D01*
G03X234809I600J800D01*
G02Y1144718I900J-1202D01*
G37*
G36*
G01X253533Y1144574D02*
G03X252333I-600J-800D01*
G02Y1146978I-900J1202D01*
G03X253533I600J800D01*
G02Y1144574I900J-1202D01*
G37*
G36*
G01X262573Y1144431D02*
G03X261373I-600J-800D01*
G02Y1146835I-900J1202D01*
G03X262573I600J800D01*
G02Y1144431I900J-1202D01*
G37*
G36*
G01X271921Y1144289D02*
G03X270721I-600J-800D01*
G02Y1146693I-900J1202D01*
G03X271921I600J800D01*
G02Y1144289I900J-1202D01*
G37*
G36*
G01X244777Y1134213D02*
G03X243577I-600J-800D01*
G02Y1136617I-900J1202D01*
G03X244777I600J800D01*
G02Y1134213I900J-1202D01*
G37*
G36*
G01X234809D02*
G03X233609I-600J-800D01*
G02Y1136617I-900J1202D01*
G03X234809I600J800D01*
G02Y1134213I900J-1202D01*
G37*
G36*
G01X253533Y1134069D02*
G03X252333I-600J-800D01*
G02Y1136473I-900J1202D01*
G03X253533I600J800D01*
G02Y1134069I900J-1202D01*
G37*
G36*
G01X262573Y1133926D02*
G03X261373I-600J-800D01*
G02Y1136330I-900J1202D01*
G03X262573I600J800D01*
G02Y1133926I900J-1202D01*
G37*
G36*
G01X271921Y1133784D02*
G03X270721I-600J-800D01*
G02Y1136188I-900J1202D01*
G03X271921I600J800D01*
G02Y1133784I900J-1202D01*
G37*
G36*
G01X244777Y1123698D02*
G03X243577I-600J-800D01*
G02Y1126102I-900J1202D01*
G03X244777I600J800D01*
G02Y1123698I900J-1202D01*
G37*
G36*
G01X234809D02*
G03X233609I-600J-800D01*
G02Y1126102I-900J1202D01*
G03X234809I600J800D01*
G02Y1123698I900J-1202D01*
G37*
G36*
G01X253533Y1123554D02*
G03X252333I-600J-800D01*
G02Y1125958I-900J1202D01*
G03X253533I600J800D01*
G02Y1123554I900J-1202D01*
G37*
G36*
G01X262573Y1123411D02*
G03X261373I-600J-800D01*
G02Y1125815I-900J1202D01*
G03X262573I600J800D01*
G02Y1123411I900J-1202D01*
G37*
G36*
G01X271921Y1123269D02*
G03X270721I-600J-800D01*
G02Y1125673I-900J1202D01*
G03X271921I600J800D01*
G02Y1123269I900J-1202D01*
G37*
G36*
G01X320140Y1032516D02*
G03X318940I-600J-800D01*
G02Y1034920I-900J1202D01*
G03X320140I600J800D01*
G02Y1032516I900J-1202D01*
G37*
G36*
G01X309099D02*
G03X307899I-600J-800D01*
G02Y1034920I-900J1202D01*
G03X309099I600J800D01*
G02Y1032516I900J-1202D01*
G37*
G36*
G01X320270Y1025879D02*
G03X319070I-600J-800D01*
G02Y1028283I-900J1202D01*
G03X320270I600J800D01*
G02Y1025879I900J-1202D01*
G37*
G36*
G01X309229D02*
G03X308029I-600J-800D01*
G02Y1028283I-900J1202D01*
G03X309229I600J800D01*
G02Y1025879I900J-1202D01*
G37*
G36*
G01X320335Y1019455D02*
G03X319135I-600J-800D01*
G02Y1021859I-900J1202D01*
G03X320335I600J800D01*
G02Y1019455I900J-1202D01*
G37*
G36*
G01X309294D02*
G03X308094I-600J-800D01*
G02Y1021859I-900J1202D01*
G03X309294I600J800D01*
G02Y1019455I900J-1202D01*
G37*
G36*
G01X320284Y1012892D02*
G03X319084I-600J-800D01*
G02Y1015296I-900J1202D01*
G03X320284I600J800D01*
G02Y1012892I900J-1202D01*
G37*
G36*
G01X309243D02*
G03X308043I-600J-800D01*
G02Y1015296I-900J1202D01*
G03X309243I600J800D01*
G02Y1012892I900J-1202D01*
G37*
G36*
G01X165524Y1010096D02*
G03X164324I-600J-800D01*
G02Y1012500I-900J1202D01*
G03X165524I600J800D01*
G02Y1010096I900J-1202D01*
G37*
G36*
G01X320219Y1006101D02*
G03X319019I-600J-800D01*
G02Y1008505I-900J1202D01*
G03X320219I600J800D01*
G02Y1006101I900J-1202D01*
G37*
G36*
G01X309178D02*
G03X307978I-600J-800D01*
G02Y1008505I-900J1202D01*
G03X309178I600J800D01*
G02Y1006101I900J-1202D01*
G37*
G36*
G01X165524Y1002368D02*
G03X164324I-600J-800D01*
G02Y1004772I-900J1202D01*
G03X165524I600J800D01*
G02Y1002368I900J-1202D01*
G37*
G36*
G01X320415Y1000084D02*
G03X319215I-600J-800D01*
G02Y1002488I-900J1202D01*
G03X320415I600J800D01*
G02Y1000084I900J-1202D01*
G37*
G36*
G01X309374D02*
G03X308174I-600J-800D01*
G02Y1002488I-900J1202D01*
G03X309374I600J800D01*
G02Y1000084I900J-1202D01*
G37*
G36*
G01X165799Y992742D02*
G03X164599I-600J-800D01*
G02Y995146I-900J1202D01*
G03X165799I600J800D01*
G02Y992742I900J-1202D01*
G37*
G36*
G01X276499Y989351D02*
G03X275299I-600J-800D01*
G02Y991755I-900J1202D01*
G03X276499I600J800D01*
G02Y989351I900J-1202D01*
G37*
G36*
G01X264721D02*
G03X263521I-600J-800D01*
G02Y991755I-900J1202D01*
G03X264721I600J800D01*
G02Y989351I900J-1202D01*
G37*
G36*
G01X165799Y982237D02*
G03X164599I-600J-800D01*
G02Y984641I-900J1202D01*
G03X165799I600J800D01*
G02Y982237I900J-1202D01*
G37*
G36*
G01X276499Y980912D02*
G03X275299I-600J-800D01*
G02Y983316I-900J1202D01*
G03X276499I600J800D01*
G02Y980912I900J-1202D01*
G37*
G36*
G01X264721D02*
G03X263521I-600J-800D01*
G02Y983316I-900J1202D01*
G03X264721I600J800D01*
G02Y980912I900J-1202D01*
G37*
G36*
G01X276499Y973184D02*
G03X275299I-600J-800D01*
G02Y975588I-900J1202D01*
G03X276499I600J800D01*
G02Y973184I900J-1202D01*
G37*
G36*
G01X264721D02*
G03X263521I-600J-800D01*
G02Y975588I-900J1202D01*
G03X264721I600J800D01*
G02Y973184I900J-1202D01*
G37*
G36*
G01X276644Y965904D02*
G03X275444I-600J-800D01*
G02Y968308I-900J1202D01*
G03X276644I600J800D01*
G02Y965904I900J-1202D01*
G37*
G36*
G01X264866D02*
G03X263666I-600J-800D01*
G02Y968308I-900J1202D01*
G03X264866I600J800D01*
G02Y965904I900J-1202D01*
G37*
G36*
G01X276644Y958657D02*
G03X275444I-600J-800D01*
G02Y961061I-900J1202D01*
G03X276644I600J800D01*
G02Y958657I900J-1202D01*
G37*
G36*
G01X264866D02*
G03X263666I-600J-800D01*
G02Y961061I-900J1202D01*
G03X264866I600J800D01*
G02Y958657I900J-1202D01*
G37*
G36*
G01X276644Y948142D02*
G03X275444I-600J-800D01*
G02Y950546I-900J1202D01*
G03X276644I600J800D01*
G02Y948142I900J-1202D01*
G37*
G36*
G01X264866D02*
G03X263666I-600J-800D01*
G02Y950546I-900J1202D01*
G03X264866I600J800D01*
G02Y948142I900J-1202D01*
G37*
G36*
G01X169982Y902727D02*
G02X170003Y902205I-6597J-527D01*
G02X156766I-6618J0D01*
G02X169982Y902727I6618J0D01*
G37*
G36*
G01X252274Y870124D02*
G03X251074I-600J-800D01*
G02Y872528I-900J1202D01*
G03X252274I600J800D01*
G02Y870124I900J-1202D01*
G37*
G36*
G01X240496D02*
G03X239296I-600J-800D01*
G02Y872528I-900J1202D01*
G03X240496I600J800D01*
G02Y870124I900J-1202D01*
G37*
G36*
G01X252274Y861685D02*
G03X251074I-600J-800D01*
G02Y864089I-900J1202D01*
G03X252274I600J800D01*
G02Y861685I900J-1202D01*
G37*
G36*
G01X240496D02*
G03X239296I-600J-800D01*
G02Y864089I-900J1202D01*
G03X240496I600J800D01*
G02Y861685I900J-1202D01*
G37*
G36*
G01X252274Y853957D02*
G03X251074I-600J-800D01*
G02Y856361I-900J1202D01*
G03X252274I600J800D01*
G02Y853957I900J-1202D01*
G37*
G36*
G01X240496D02*
G03X239296I-600J-800D01*
G02Y856361I-900J1202D01*
G03X240496I600J800D01*
G02Y853957I900J-1202D01*
G37*
G36*
G01X257121Y769747D02*
G03X255921I-600J-800D01*
G02Y772151I-900J1202D01*
G03X257121I600J800D01*
G02Y769747I900J-1202D01*
G37*
G36*
G01X246080D02*
G03X244880I-600J-800D01*
G02Y772151I-900J1202D01*
G03X246080I600J800D01*
G02Y769747I900J-1202D01*
G37*
G36*
G01X236112D02*
G03X234912I-600J-800D01*
G02Y772151I-900J1202D01*
G03X236112I600J800D01*
G02Y769747I900J-1202D01*
G37*
G36*
G01X257121Y761308D02*
G03X255921I-600J-800D01*
G02Y763712I-900J1202D01*
G03X257121I600J800D01*
G02Y761308I900J-1202D01*
G37*
G36*
G01X246080D02*
G03X244880I-600J-800D01*
G02Y763712I-900J1202D01*
G03X246080I600J800D01*
G02Y761308I900J-1202D01*
G37*
G36*
G01X236112D02*
G03X234912I-600J-800D01*
G02Y763712I-900J1202D01*
G03X236112I600J800D01*
G02Y761308I900J-1202D01*
G37*
G36*
G01X257121Y753580D02*
G03X255921I-600J-800D01*
G02Y755984I-900J1202D01*
G03X257121I600J800D01*
G02Y753580I900J-1202D01*
G37*
G36*
G01X246080D02*
G03X244880I-600J-800D01*
G02Y755984I-900J1202D01*
G03X246080I600J800D01*
G02Y753580I900J-1202D01*
G37*
G36*
G01X236112D02*
G03X234912I-600J-800D01*
G02Y755984I-900J1202D01*
G03X236112I600J800D01*
G02Y753580I900J-1202D01*
G37*
G36*
G01X317287Y696065D02*
G03X316087I-600J-800D01*
G02Y698469I-900J1202D01*
G03X317287I600J800D01*
G02Y696065I900J-1202D01*
G37*
G36*
G01X306246D02*
G03X305046I-600J-800D01*
G02Y698469I-900J1202D01*
G03X306246I600J800D01*
G02Y696065I900J-1202D01*
G37*
G36*
G01X317287Y687626D02*
G03X316087I-600J-800D01*
G02Y690030I-900J1202D01*
G03X317287I600J800D01*
G02Y687626I900J-1202D01*
G37*
G36*
G01X306246D02*
G03X305046I-600J-800D01*
G02Y690030I-900J1202D01*
G03X306246I600J800D01*
G02Y687626I900J-1202D01*
G37*
G36*
G01X317287Y679898D02*
G03X316087I-600J-800D01*
G02Y682302I-900J1202D01*
G03X317287I600J800D01*
G02Y679898I900J-1202D01*
G37*
G36*
G01X306246D02*
G03X305046I-600J-800D01*
G02Y682302I-900J1202D01*
G03X306246I600J800D01*
G02Y679898I900J-1202D01*
G37*
G36*
G01X317287Y670561D02*
G03X316087I-600J-800D01*
G02Y672965I-900J1202D01*
G03X317287I600J800D01*
G02Y670561I900J-1202D01*
G37*
G36*
G01X306246D02*
G03X305046I-600J-800D01*
G02Y672965I-900J1202D01*
G03X306246I600J800D01*
G02Y670561I900J-1202D01*
G37*
G36*
G01X317287Y660056D02*
G03X316087I-600J-800D01*
G02Y662460I-900J1202D01*
G03X317287I600J800D01*
G02Y660056I900J-1202D01*
G37*
G36*
G01X306246D02*
G03X305046I-600J-800D01*
G02Y662460I-900J1202D01*
G03X306246I600J800D01*
G02Y660056I900J-1202D01*
G37*
G36*
G01X317287Y651255D02*
G03X316087I-600J-800D01*
G02Y653659I-900J1202D01*
G03X317287I600J800D01*
G02Y651255I900J-1202D01*
G37*
G36*
G01X306246D02*
G03X305046I-600J-800D01*
G02Y653659I-900J1202D01*
G03X306246I600J800D01*
G02Y651255I900J-1202D01*
G37*
G36*
G01X159372Y648381D02*
G03X158172I-600J-800D01*
G02Y650785I-900J1202D01*
G03X159372I600J800D01*
G02Y648381I900J-1202D01*
G37*
G36*
G01Y639942D02*
G03X158172I-600J-800D01*
G02Y642346I-900J1202D01*
G03X159372I600J800D01*
G02Y639942I900J-1202D01*
G37*
G36*
G01Y632214D02*
G03X158172I-600J-800D01*
G02Y634618I-900J1202D01*
G03X159372I600J800D01*
G02Y632214I900J-1202D01*
G37*
G36*
G01Y622877D02*
G03X158172I-600J-800D01*
G02Y625281I-900J1202D01*
G03X159372I600J800D01*
G02Y622877I900J-1202D01*
G37*
G36*
G01X278044Y616247D02*
G03X276844I-600J-800D01*
G02Y618651I-900J1202D01*
G03X278044I600J800D01*
G02Y616247I900J-1202D01*
G37*
G36*
G01X266266D02*
G03X265066I-600J-800D01*
G02Y618651I-900J1202D01*
G03X266266I600J800D01*
G02Y616247I900J-1202D01*
G37*
G36*
G01X159372Y612372D02*
G03X158172I-600J-800D01*
G02Y614776I-900J1202D01*
G03X159372I600J800D01*
G02Y612372I900J-1202D01*
G37*
G36*
G01X278044Y607808D02*
G03X276844I-600J-800D01*
G02Y610212I-900J1202D01*
G03X278044I600J800D01*
G02Y607808I900J-1202D01*
G37*
G36*
G01X266266D02*
G03X265066I-600J-800D01*
G02Y610212I-900J1202D01*
G03X266266I600J800D01*
G02Y607808I900J-1202D01*
G37*
G36*
G01X159372Y603571D02*
G03X158172I-600J-800D01*
G02Y605975I-900J1202D01*
G03X159372I600J800D01*
G02Y603571I900J-1202D01*
G37*
G36*
G01X278044Y600080D02*
G03X276844I-600J-800D01*
G02Y602484I-900J1202D01*
G03X278044I600J800D01*
G02Y600080I900J-1202D01*
G37*
G36*
G01X266266D02*
G03X265066I-600J-800D01*
G02Y602484I-900J1202D01*
G03X266266I600J800D01*
G02Y600080I900J-1202D01*
G37*
G36*
G01X278044Y590743D02*
G03X276844I-600J-800D01*
G02Y593147I-900J1202D01*
G03X278044I600J800D01*
G02Y590743I900J-1202D01*
G37*
G36*
G01X266266D02*
G03X265066I-600J-800D01*
G02Y593147I-900J1202D01*
G03X266266I600J800D01*
G02Y590743I900J-1202D01*
G37*
G36*
G01X278044Y580238D02*
G03X276844I-600J-800D01*
G02Y582642I-900J1202D01*
G03X278044I600J800D01*
G02Y580238I900J-1202D01*
G37*
G36*
G01X266266D02*
G03X265066I-600J-800D01*
G02Y582642I-900J1202D01*
G03X266266I600J800D01*
G02Y580238I900J-1202D01*
G37*
G36*
G01X278044Y571437D02*
G03X276844I-600J-800D01*
G02Y573841I-900J1202D01*
G03X278044I600J800D01*
G02Y571437I900J-1202D01*
G37*
G36*
G01X266266D02*
G03X265066I-600J-800D01*
G02Y573841I-900J1202D01*
G03X266266I600J800D01*
G02Y571437I900J-1202D01*
G37*
G36*
G01X315891Y531669D02*
G03X314691I-600J-800D01*
G02Y534073I-900J1202D01*
G03X315891I600J800D01*
G02Y531669I900J-1202D01*
G37*
G36*
G01X324239Y531597D02*
G03X323039I-600J-800D01*
G02Y534001I-900J1202D01*
G03X324239I600J800D01*
G02Y531597I900J-1202D01*
G37*
G36*
G01X291669Y531560D02*
G03X290469I-600J-800D01*
G02Y533964I-900J1202D01*
G03X291669I600J800D01*
G02Y531560I900J-1202D01*
G37*
G36*
G01X307066Y531384D02*
G03X305866I-600J-800D01*
G02Y533788I-900J1202D01*
G03X307066I600J800D01*
G02Y531384I900J-1202D01*
G37*
G36*
G01X299637Y531274D02*
G03X298437I-600J-800D01*
G02Y533678I-900J1202D01*
G03X299637I600J800D01*
G02Y531274I900J-1202D01*
G37*
G36*
G01X315891Y523230D02*
G03X314691I-600J-800D01*
G02Y525634I-900J1202D01*
G03X315891I600J800D01*
G02Y523230I900J-1202D01*
G37*
G36*
G01X324239Y523158D02*
G03X323039I-600J-800D01*
G02Y525562I-900J1202D01*
G03X324239I600J800D01*
G02Y523158I900J-1202D01*
G37*
G36*
G01X291669Y523121D02*
G03X290469I-600J-800D01*
G02Y525525I-900J1202D01*
G03X291669I600J800D01*
G02Y523121I900J-1202D01*
G37*
G36*
G01X307066Y522945D02*
G03X305866I-600J-800D01*
G02Y525349I-900J1202D01*
G03X307066I600J800D01*
G02Y522945I900J-1202D01*
G37*
G36*
G01X299637Y522835D02*
G03X298437I-600J-800D01*
G02Y525239I-900J1202D01*
G03X299637I600J800D01*
G02Y522835I900J-1202D01*
G37*
G36*
G01X315891Y515502D02*
G03X314691I-600J-800D01*
G02Y517906I-900J1202D01*
G03X315891I600J800D01*
G02Y515502I900J-1202D01*
G37*
G36*
G01X324239Y515430D02*
G03X323039I-600J-800D01*
G02Y517834I-900J1202D01*
G03X324239I600J800D01*
G02Y515430I900J-1202D01*
G37*
G36*
G01X291669Y515393D02*
G03X290469I-600J-800D01*
G02Y517797I-900J1202D01*
G03X291669I600J800D01*
G02Y515393I900J-1202D01*
G37*
G36*
G01X307066Y515217D02*
G03X305866I-600J-800D01*
G02Y517621I-900J1202D01*
G03X307066I600J800D01*
G02Y515217I900J-1202D01*
G37*
G36*
G01X299637Y515107D02*
G03X298437I-600J-800D01*
G02Y517511I-900J1202D01*
G03X299637I600J800D01*
G02Y515107I900J-1202D01*
G37*
G36*
G01X249916Y420141D02*
G03Y418941I800J-600D01*
G02X247512I-1202J-900D01*
G03Y420141I-800J600D01*
G02X249916I1202J900D01*
G37*
G36*
G01X240948Y419998D02*
G03Y418798I800J-600D01*
G02X238544I-1202J-900D01*
G03Y419998I-800J600D01*
G02X240948I1202J900D01*
G37*
G36*
G01X275733Y419894D02*
G03Y418694I800J-600D01*
G02X273329I-1202J-900D01*
G03Y419894I-800J600D01*
G02X275733I1202J900D01*
G37*
G36*
G01X267242Y419751D02*
G03Y418551I800J-600D01*
G02X264838I-1202J-900D01*
G03Y419751I-800J600D01*
G02X267242I1202J900D01*
G37*
G36*
G01X258774Y419750D02*
G03Y418550I800J-600D01*
G02X256370I-1202J-900D01*
G03Y419750I-800J600D01*
G02X258774I1202J900D01*
G37*
G36*
G01X249916Y409636D02*
G03Y408436I800J-600D01*
G02X247512I-1202J-900D01*
G03Y409636I-800J600D01*
G02X249916I1202J900D01*
G37*
G36*
G01X240948Y409493D02*
G03Y408293I800J-600D01*
G02X238544I-1202J-900D01*
G03Y409493I-800J600D01*
G02X240948I1202J900D01*
G37*
G36*
G01X275733Y409389D02*
G03Y408189I800J-600D01*
G02X273329I-1202J-900D01*
G03Y409389I-800J600D01*
G02X275733I1202J900D01*
G37*
G36*
G01X267242Y409246D02*
G03Y408046I800J-600D01*
G02X264838I-1202J-900D01*
G03Y409246I-800J600D01*
G02X267242I1202J900D01*
G37*
G36*
G01X258774Y409245D02*
G03Y408045I800J-600D01*
G02X256370I-1202J-900D01*
G03Y409245I-800J600D01*
G02X258774I1202J900D01*
G37*
G36*
G01X249916Y399121D02*
G03Y397921I800J-600D01*
G02X247512I-1202J-900D01*
G03Y399121I-800J600D01*
G02X249916I1202J900D01*
G37*
G36*
G01X240948Y398978D02*
G03Y397778I800J-600D01*
G02X238544I-1202J-900D01*
G03Y398978I-800J600D01*
G02X240948I1202J900D01*
G37*
G36*
G01X275733Y398874D02*
G03Y397674I800J-600D01*
G02X273329I-1202J-900D01*
G03Y398874I-800J600D01*
G02X275733I1202J900D01*
G37*
G36*
G01X267242Y398731D02*
G03Y397531I800J-600D01*
G02X264838I-1202J-900D01*
G03Y398731I-800J600D01*
G02X267242I1202J900D01*
G37*
G36*
G01X258774Y398730D02*
G03Y397530I800J-600D01*
G02X256370I-1202J-900D01*
G03Y398730I-800J600D01*
G02X258774I1202J900D01*
G37*
G36*
G01X342826Y347453D02*
G03X341626I-600J-800D01*
G02Y349857I-900J1202D01*
G03X342826I600J800D01*
G02Y347453I900J-1202D01*
G37*
G36*
G01X331785D02*
G03X330585I-600J-800D01*
G02Y349857I-900J1202D01*
G03X331785I600J800D01*
G02Y347453I900J-1202D01*
G37*
G36*
G01X342916Y341259D02*
G03X341716I-600J-800D01*
G02Y343663I-900J1202D01*
G03X342916I600J800D01*
G02Y341259I900J-1202D01*
G37*
G36*
G01X331875D02*
G03X330675I-600J-800D01*
G02Y343663I-900J1202D01*
G03X331875I600J800D01*
G02Y341259I900J-1202D01*
G37*
G36*
G01X342916Y334070D02*
G03X341716I-600J-800D01*
G02Y336474I-900J1202D01*
G03X342916I600J800D01*
G02Y334070I900J-1202D01*
G37*
G36*
G01X331875D02*
G03X330675I-600J-800D01*
G02Y336474I-900J1202D01*
G03X331875I600J800D01*
G02Y334070I900J-1202D01*
G37*
G36*
G01X342916Y324733D02*
G03X341716I-600J-800D01*
G02Y327137I-900J1202D01*
G03X342916I600J800D01*
G02Y324733I900J-1202D01*
G37*
G36*
G01X331875D02*
G03X330675I-600J-800D01*
G02Y327137I-900J1202D01*
G03X331875I600J800D01*
G02Y324733I900J-1202D01*
G37*
G36*
G01X342916Y317432D02*
G03X341716I-600J-800D01*
G02Y319836I-900J1202D01*
G03X342916I600J800D01*
G02Y317432I900J-1202D01*
G37*
G36*
G01X331875D02*
G03X330675I-600J-800D01*
G02Y319836I-900J1202D01*
G03X331875I600J800D01*
G02Y317432I900J-1202D01*
G37*
G36*
G01X168075Y311105D02*
G03X166875I-600J-800D01*
G02Y313509I-900J1202D01*
G03X168075I600J800D01*
G02Y311105I900J-1202D01*
G37*
G36*
G01X342834Y310778D02*
G03X341634I-600J-800D01*
G02Y313182I-900J1202D01*
G03X342834I600J800D01*
G02Y310778I900J-1202D01*
G37*
G36*
G01X331793D02*
G03X330593I-600J-800D01*
G02Y313182I-900J1202D01*
G03X331793I600J800D01*
G02Y310778I900J-1202D01*
G37*
G36*
G01X168075Y302666D02*
G03X166875I-600J-800D01*
G02Y305070I-900J1202D01*
G03X168075I600J800D01*
G02Y302666I900J-1202D01*
G37*
G36*
G01Y294938D02*
G03X166875I-600J-800D01*
G02Y297342I-900J1202D01*
G03X168075I600J800D01*
G02Y294938I900J-1202D01*
G37*
G36*
G01Y285601D02*
G03X166875I-600J-800D01*
G02Y288005I-900J1202D01*
G03X168075I600J800D01*
G02Y285601I900J-1202D01*
G37*
G36*
G01Y275096D02*
G03X166875I-600J-800D01*
G02Y277500I-900J1202D01*
G03X168075I600J800D01*
G02Y275096I900J-1202D01*
G37*
G36*
G01X263696Y266986D02*
G03X262496I-600J-800D01*
G02Y269390I-900J1202D01*
G03X263696I600J800D01*
G02Y266986I900J-1202D01*
G37*
G36*
G01X254918D02*
G03X253718I-600J-800D01*
G02Y269390I-900J1202D01*
G03X254918I600J800D01*
G02Y266986I900J-1202D01*
G37*
G36*
G01X168075Y264581D02*
G03X166875I-600J-800D01*
G02Y266985I-900J1202D01*
G03X168075I600J800D01*
G02Y264581I900J-1202D01*
G37*
G36*
G01X263696Y258547D02*
G03X262496I-600J-800D01*
G02Y260951I-900J1202D01*
G03X263696I600J800D01*
G02Y258547I900J-1202D01*
G37*
G36*
G01X254918D02*
G03X253718I-600J-800D01*
G02Y260951I-900J1202D01*
G03X254918I600J800D01*
G02Y258547I900J-1202D01*
G37*
G36*
G01X263696Y250819D02*
G03X262496I-600J-800D01*
G02Y253223I-900J1202D01*
G03X263696I600J800D01*
G02Y250819I900J-1202D01*
G37*
G36*
G01X254918D02*
G03X253718I-600J-800D01*
G02Y253223I-900J1202D01*
G03X254918I600J800D01*
G02Y250819I900J-1202D01*
G37*
G36*
G01X263696Y241482D02*
G03X262496I-600J-800D01*
G02Y243886I-900J1202D01*
G03X263696I600J800D01*
G02Y241482I900J-1202D01*
G37*
G36*
G01X254918D02*
G03X253718I-600J-800D01*
G02Y243886I-900J1202D01*
G03X254918I600J800D01*
G02Y241482I900J-1202D01*
G37*
G36*
G01X263696Y230977D02*
G03X262496I-600J-800D01*
G02Y233381I-900J1202D01*
G03X263696I600J800D01*
G02Y230977I900J-1202D01*
G37*
G36*
G01X254918D02*
G03X253718I-600J-800D01*
G02Y233381I-900J1202D01*
G03X254918I600J800D01*
G02Y230977I900J-1202D01*
G37*
G36*
G01X263696Y220462D02*
G03X262496I-600J-800D01*
G02Y222866I-900J1202D01*
G03X263696I600J800D01*
G02Y220462I900J-1202D01*
G37*
G36*
G01X254918D02*
G03X253718I-600J-800D01*
G02Y222866I-900J1202D01*
G03X254918I600J800D01*
G02Y220462I900J-1202D01*
G37*
G36*
G01X169982Y202727D02*
G02X170002Y202205I-6597J-514D01*
G02X156766I-6618J0D01*
G02X169982Y202727I6618J0D01*
G37*
G36*
G01X258063Y172231D02*
G03Y171031I800J-600D01*
G02X255659I-1202J-900D01*
G03Y172231I-800J600D01*
G02X258063I1202J900D01*
G37*
G36*
G01X249285D02*
G03Y171031I800J-600D01*
G02X246881I-1202J-900D01*
G03Y172231I-800J600D01*
G02X249285I1202J900D01*
G37*
G36*
G01X239943D02*
G03Y171031I800J-600D01*
G02X237539I-1202J-900D01*
G03Y172231I-800J600D01*
G02X239943I1202J900D01*
G37*
G36*
G01X228902D02*
G03Y171031I800J-600D01*
G02X226498I-1202J-900D01*
G03Y172231I-800J600D01*
G02X228902I1202J900D01*
G37*
G36*
G01X218934D02*
G03Y171031I800J-600D01*
G02X216530I-1202J-900D01*
G03Y172231I-800J600D01*
G02X218934I1202J900D01*
G37*
G36*
G01X258063Y163792D02*
G03Y162592I800J-600D01*
G02X255659I-1202J-900D01*
G03Y163792I-800J600D01*
G02X258063I1202J900D01*
G37*
G36*
G01X249285D02*
G03Y162592I800J-600D01*
G02X246881I-1202J-900D01*
G03Y163792I-800J600D01*
G02X249285I1202J900D01*
G37*
G36*
G01X239943D02*
G03Y162592I800J-600D01*
G02X237539I-1202J-900D01*
G03Y163792I-800J600D01*
G02X239943I1202J900D01*
G37*
G36*
G01X228902D02*
G03Y162592I800J-600D01*
G02X226498I-1202J-900D01*
G03Y163792I-800J600D01*
G02X228902I1202J900D01*
G37*
G36*
G01X218934D02*
G03Y162592I800J-600D01*
G02X216530I-1202J-900D01*
G03Y163792I-800J600D01*
G02X218934I1202J900D01*
G37*
G36*
G01X258063Y156064D02*
G03Y154864I800J-600D01*
G02X255659I-1202J-900D01*
G03Y156064I-800J600D01*
G02X258063I1202J900D01*
G37*
G36*
G01X249285D02*
G03Y154864I800J-600D01*
G02X246881I-1202J-900D01*
G03Y156064I-800J600D01*
G02X249285I1202J900D01*
G37*
G36*
G01X239943D02*
G03Y154864I800J-600D01*
G02X237539I-1202J-900D01*
G03Y156064I-800J600D01*
G02X239943I1202J900D01*
G37*
G36*
G01X228902D02*
G03Y154864I800J-600D01*
G02X226498I-1202J-900D01*
G03Y156064I-800J600D01*
G02X228902I1202J900D01*
G37*
G36*
G01X218934D02*
G03Y154864I800J-600D01*
G02X216530I-1202J-900D01*
G03Y156064I-800J600D01*
G02X218934I1202J900D01*
G37*
G36*
G01X289304Y67549D02*
G03Y66349I800J-600D01*
G02X286900I-1202J-900D01*
G03Y67549I-800J600D01*
G02X289304I1202J900D01*
G37*
G36*
G01X280956D02*
G03Y66349I800J-600D01*
G02X278552I-1202J-900D01*
G03Y67549I-800J600D01*
G02X280956I1202J900D01*
G37*
G36*
G01X272774D02*
G03Y66349I800J-600D01*
G02X270370I-1202J-900D01*
G03Y67549I-800J600D01*
G02X272774I1202J900D01*
G37*
G36*
G01X265306D02*
G03Y66349I800J-600D01*
G02X262902I-1202J-900D01*
G03Y67549I-800J600D01*
G02X265306I1202J900D01*
G37*
G36*
G01X257768D02*
G03Y66349I800J-600D01*
G02X255364I-1202J-900D01*
G03Y67549I-800J600D01*
G02X257768I1202J900D01*
G37*
G36*
G01X289304Y57044D02*
G03Y55844I800J-600D01*
G02X286900I-1202J-900D01*
G03Y57044I-800J600D01*
G02X289304I1202J900D01*
G37*
G36*
G01X280956D02*
G03Y55844I800J-600D01*
G02X278552I-1202J-900D01*
G03Y57044I-800J600D01*
G02X280956I1202J900D01*
G37*
G36*
G01X272774D02*
G03Y55844I800J-600D01*
G02X270370I-1202J-900D01*
G03Y57044I-800J600D01*
G02X272774I1202J900D01*
G37*
G36*
G01X265306D02*
G03Y55844I800J-600D01*
G02X262902I-1202J-900D01*
G03Y57044I-800J600D01*
G02X265306I1202J900D01*
G37*
G36*
G01X257768D02*
G03Y55844I800J-600D01*
G02X255364I-1202J-900D01*
G03Y57044I-800J600D01*
G02X257768I1202J900D01*
G37*
G36*
G01X289304Y47672D02*
G03Y46472I800J-600D01*
G02X286900I-1202J-900D01*
G03Y47672I-800J600D01*
G02X289304I1202J900D01*
G37*
G36*
G01X280956D02*
G03Y46472I800J-600D01*
G02X278552I-1202J-900D01*
G03Y47672I-800J600D01*
G02X280956I1202J900D01*
G37*
G36*
G01X272774D02*
G03Y46472I800J-600D01*
G02X270370I-1202J-900D01*
G03Y47672I-800J600D01*
G02X272774I1202J900D01*
G37*
G36*
G01X265306D02*
G03Y46472I800J-600D01*
G02X262902I-1202J-900D01*
G03Y47672I-800J600D01*
G02X265306I1202J900D01*
G37*
G36*
G01X257768D02*
G03Y46472I800J-600D01*
G02X255364I-1202J-900D01*
G03Y47672I-800J600D01*
G02X257768I1202J900D01*
G37*
G36*
G01X169982Y27727D02*
G02X170002Y27205I-6597J-514D01*
G02X156766I-6618J0D01*
G02X169982Y27727I6618J0D01*
G37*
G36*
G01X301249Y1922901D02*
G02Y1925305I-900J1202D01*
G03X302449I600J800D01*
G02X304465Y1925108I900J-1202D01*
G03X306010Y1925180I743J669D01*
G02X308115Y1925485I1205J-897D01*
G03X309315I600J800D01*
G02Y1923081I900J-1202D01*
G03X308115I-600J-800D01*
G02X306099Y1923278I-900J1202D01*
G03X304554Y1923206I-743J-669D01*
G02X302449Y1922901I-1205J897D01*
G03X301249I-600J-800D01*
G37*
G36*
G01Y1915946D02*
G02Y1918350I-900J1202D01*
G03X302449I600J800D01*
G02X304465Y1918153I900J-1202D01*
G03X306010Y1918225I743J669D01*
G02X308115Y1918530I1205J-897D01*
G03X309315I600J800D01*
G02Y1916126I900J-1202D01*
G03X308115I-600J-800D01*
G02X306099Y1916323I-900J1202D01*
G03X304554Y1916251I-743J-669D01*
G02X302449Y1915946I-1205J897D01*
G03X301249I-600J-800D01*
G37*
G36*
G01Y1909030D02*
G02Y1911434I-900J1202D01*
G03X302449I600J800D01*
G02X304465Y1911237I900J-1202D01*
G03X306010Y1911309I743J669D01*
G02X308115Y1911614I1205J-897D01*
G03X309315I600J800D01*
G02Y1909210I900J-1202D01*
G03X308115I-600J-800D01*
G02X306099Y1909407I-900J1202D01*
G03X304554Y1909335I-743J-669D01*
G02X302449Y1909030I-1205J897D01*
G03X301249I-600J-800D01*
G37*
G36*
G01X81440Y1769626D02*
G02X79312I-1064J-1060D01*
G03Y1771038I-708J706D01*
G02X79306Y1773152I1064J1060D01*
G03Y1774555I-713J701D01*
G02X81446I1070J1054D01*
G03Y1773152I713J-701D01*
G02X81440Y1771038I-1070J-1054D01*
G03Y1769626I708J-706D01*
G37*
G36*
G01X269434Y1546808D02*
G02Y1549212I-900J1202D01*
G03X270634I600J800D01*
G02X272650Y1549015I900J-1202D01*
G03X274195Y1549087I743J669D01*
G02X276300Y1549392I1205J-897D01*
G03X277500I600J800D01*
G02Y1546988I900J-1202D01*
G03X276300I-600J-800D01*
G02X274284Y1547185I-900J1202D01*
G03X272739Y1547113I-743J-669D01*
G02X270634Y1546808I-1205J897D01*
G03X269434I-600J-800D01*
G37*
G36*
G01Y1539853D02*
G02Y1542257I-900J1202D01*
G03X270634I600J800D01*
G02X272650Y1542060I900J-1202D01*
G03X274195Y1542132I743J669D01*
G02X276300Y1542437I1205J-897D01*
G03X277500I600J800D01*
G02Y1540033I900J-1202D01*
G03X276300I-600J-800D01*
G02X274284Y1540230I-900J1202D01*
G03X272739Y1540158I-743J-669D01*
G02X270634Y1539853I-1205J897D01*
G03X269434I-600J-800D01*
G37*
G36*
G01Y1532937D02*
G02Y1535341I-900J1202D01*
G03X270634I600J800D01*
G02X272650Y1535144I900J-1202D01*
G03X274195Y1535216I743J669D01*
G02X276300Y1535521I1205J-897D01*
G03X277500I600J800D01*
G02Y1533117I900J-1202D01*
G03X276300I-600J-800D01*
G02X274284Y1533314I-900J1202D01*
G03X272739Y1533242I-743J-669D01*
G02X270634Y1532937I-1205J897D01*
G03X269434I-600J-800D01*
G37*
G36*
G01X94431Y418629D02*
G02X92690Y419140I-1208J-893D01*
G03X93139Y420669I-355J935D01*
G02X94880Y420158I1208J893D01*
G03X94431Y418629I355J-935D01*
G37*
G36*
G01X26828Y1054605D02*
G02X20471Y1060962I-6357J0D01*
G01Y1060963D01*
X20472D01*
G02X26828Y1054605I-1J-6357D01*
G37*
G36*
G01X26118Y987262D02*
G02X14103Y984333I-5650J-2929D01*
G02X14817Y987263I6365J1D01*
G03X14391Y988610I-888J460D01*
G02X17996Y991340I1156J2219D01*
G03X19178Y990566I979J205D01*
G02X21758Y990565I1288J-6233D01*
G03X22940Y991340I203J979D01*
G02X26544Y988610I2449J-511D01*
G03X26118Y987262I462J-887D01*
G37*
G36*
G01X49622Y867096D02*
G02X47264Y867122I-1189J-917D01*
G03X47278Y868361I-778J628D01*
G02X49636Y868335I1189J917D01*
G03X49622Y867096I778J-628D01*
G37*
G54D66*
X226573Y2031480D03*
X236541D03*
X226573Y2020965D03*
X236541D03*
X242582D03*
Y2031480D03*
X231541Y2020965D03*
X221573D03*
X231541Y2031480D03*
X221573D03*
X226573Y2059050D03*
X236541Y2051322D03*
Y2059050D03*
X226573Y2041985D03*
Y2051322D03*
X236541Y2041985D03*
X242582Y2059050D03*
Y2051322D03*
Y2041985D03*
X231541D03*
X221573Y2051322D03*
Y2041985D03*
X231541Y2059050D03*
Y2051322D03*
X221573Y2059050D03*
X236541Y2067489D03*
X226573D03*
X242582D03*
X221573D03*
X231541D03*
X247582Y2031480D03*
Y2020965D03*
X260337D03*
Y2031480D03*
X267115Y2020965D03*
Y2031480D03*
X255337D03*
Y2020965D03*
X247582Y2041985D03*
Y2051322D03*
Y2059050D03*
X260337Y2051322D03*
Y2059050D03*
Y2041985D03*
X267115D03*
Y2059050D03*
Y2051322D03*
X255337Y2041985D03*
Y2059050D03*
Y2051322D03*
X260337Y2067489D03*
X247582D03*
X267115D03*
X255337D03*
X272115Y2031480D03*
Y2020965D03*
Y2051322D03*
Y2059050D03*
Y2041985D03*
Y2067489D03*
X292614Y1864565D03*
X323403Y1172804D03*
X59127Y1257647D03*
X58356Y1279812D03*
X58416Y1272383D03*
X70340Y1328203D03*
G54D68*
X15547Y770357D03*
Y778231D03*
X25389Y770357D03*
Y778231D03*
X15547Y786105D03*
Y801853D03*
X25389Y786105D03*
X15547Y809727D03*
Y817601D03*
Y833349D03*
Y841223D03*
Y849097D03*
X25389D03*
X15547Y856971D03*
Y872719D03*
X25389Y856971D03*
Y864845D03*
X15547Y880593D03*
Y888467D03*
Y896341D03*
X25389Y880593D03*
Y888467D03*
Y896341D03*
X15547Y912089D03*
Y919963D03*
X25389Y904215D03*
Y919963D03*
X15547Y927837D03*
Y935711D03*
Y951459D03*
X25389Y927837D03*
Y935711D03*
Y943585D03*
X15547Y959333D03*
Y967207D03*
Y975081D03*
X25389Y959333D03*
Y967207D03*
Y975081D03*
Y998703D03*
X15547Y1006577D03*
Y1014451D03*
Y1022325D03*
X25389Y1014451D03*
Y1022325D03*
X15551Y1065629D03*
X25393D03*
X15551Y1073503D03*
Y1081377D03*
X25393D03*
Y1089251D03*
X15551Y1097125D03*
Y1104999D03*
Y1112873D03*
Y1120748D03*
X25393Y1097125D03*
Y1104999D03*
Y1120748D03*
X15551Y1136496D03*
Y1144370D03*
X25393Y1128622D03*
Y1136496D03*
Y1144370D03*
X15551Y1152244D03*
Y1160118D03*
X25393D03*
Y1167992D03*
X15551Y1175866D03*
Y1183740D03*
Y1191614D03*
X25393Y1175866D03*
Y1183740D03*
X15551Y1199488D03*
Y1215236D03*
X25393Y1199488D03*
Y1207362D03*
Y1215236D03*
X15551Y1223110D03*
Y1230984D03*
Y1238858D03*
X25393Y1223110D03*
Y1238858D03*
X15551Y1254606D03*
Y1262480D03*
X25393Y1246732D03*
Y1254606D03*
X33263Y774293D03*
Y782167D03*
Y845160D03*
Y860908D03*
Y868782D03*
Y876656D03*
Y884530D03*
Y900278D03*
Y908152D03*
Y916026D03*
Y923900D03*
Y939648D03*
Y947522D03*
Y955396D03*
Y963270D03*
Y979018D03*
Y994766D03*
Y1002640D03*
Y1010514D03*
Y1026262D03*
X33267Y1061692D03*
Y1069566D03*
Y1077440D03*
Y1085314D03*
Y1101062D03*
Y1108936D03*
Y1116810D03*
Y1124684D03*
Y1140432D03*
Y1148306D03*
Y1156180D03*
Y1164055D03*
Y1179803D03*
Y1187677D03*
Y1195551D03*
Y1203425D03*
Y1219173D03*
Y1227047D03*
Y1234921D03*
Y1242795D03*
G54D60*
X107025Y725368D03*
X107173Y735219D03*
X144878Y1738861D03*
X157558Y51426D03*
X164037Y1400226D03*
X170351Y1401324D03*
X163257Y1737619D03*
X150309Y1737009D03*
X168151Y1739208D03*
X165782Y1732903D03*
X156183Y1735240D03*
X175022Y980281D03*
X175742Y989958D03*
X175449Y997660D03*
X175698Y1008730D03*
X176083Y1402321D03*
X173394Y1736051D03*
X256947Y128276D03*
X257125Y115559D03*
X265722Y463102D03*
X265737Y473680D03*
X255837Y823626D03*
X255687Y812192D03*
X280240Y1858668D03*
X279976Y1864565D03*
X308057Y248863D03*
X306267Y241010D03*
X314914Y238162D03*
X314940Y252083D03*
X309678Y1053262D03*
X312527Y1162266D03*
X312698Y1172804D03*
X314183Y1403423D03*
X302267Y1524401D03*
X301734Y1513883D03*
X312077Y1575871D03*
X331403Y51409D03*
X333889Y56021D03*
X338227Y61559D03*
X320372Y225979D03*
X318088Y231820D03*
X321899Y238137D03*
X331046Y232021D03*
X320961Y250105D03*
X324709Y231580D03*
X335522Y404033D03*
X323313Y418313D03*
X326196Y413982D03*
X328950Y409216D03*
X320980Y423225D03*
X336617Y577978D03*
X329636Y584715D03*
X317724Y588250D03*
X337387Y586230D03*
X320380Y576491D03*
X331867Y589810D03*
X333750Y595326D03*
X331568Y752967D03*
X339012Y752859D03*
X329336Y762693D03*
X334010Y758588D03*
X327524Y758020D03*
X329938Y948756D03*
X332527Y943746D03*
X324098Y946104D03*
X318557Y941178D03*
X323868Y929978D03*
X326646Y939788D03*
X336160Y937262D03*
X328583Y933262D03*
X321425Y951577D03*
X324246Y1051786D03*
X335677Y1048904D03*
X317592Y1053050D03*
X337509Y1109598D03*
X328989Y1121090D03*
X326558Y1126368D03*
X327452Y1279447D03*
X321978Y1282086D03*
X329619Y1284016D03*
X327932Y1289221D03*
X325636Y1399114D03*
X334646Y1400804D03*
X323720Y1570924D03*
X333474Y1566686D03*
X335963Y1573797D03*
X323813Y1753231D03*
X329887Y1752081D03*
X332399Y1926787D03*
X359931Y52189D03*
X348289Y50863D03*
X345089Y56190D03*
X340373Y51579D03*
X342097Y401684D03*
X363825Y401768D03*
X342900Y580126D03*
X362577Y752783D03*
X344109Y751809D03*
X343656Y933725D03*
X345578Y1047844D03*
X344099Y1106798D03*
X344130Y1401670D03*
X350690Y1403243D03*
X348710Y1570187D03*
X361011Y1568890D03*
X343402Y1572080D03*
X348245Y1575241D03*
X355364Y1570990D03*
X345537Y1916558D03*
X344402Y1911123D03*
X363361Y1918313D03*
X363411Y1923459D03*
X340336Y1922409D03*
X372204Y56126D03*
X379257Y52158D03*
X387524Y76847D03*
X374442Y406857D03*
X374542Y401282D03*
X368907Y404308D03*
X376654Y754748D03*
X382892Y767710D03*
X386790Y774338D03*
X379335Y1189778D03*
X383276Y1184136D03*
X386816Y1179841D03*
X376472Y1194999D03*
X373674Y1199967D03*
X367829Y1566108D03*
X374775Y1919243D03*
X379403Y1917261D03*
X369748Y1921795D03*
X49441Y1238962D03*
X61866Y1309190D03*
X54543Y1308995D03*
X67568Y1307829D03*
X61866Y1342104D03*
G54D54*
X22480Y328649D03*
G54D67*
X253385Y21890D03*
Y32520D03*
X263385Y21890D03*
Y32520D03*
X253385Y196890D03*
X263385D03*
X253385Y207520D03*
X263385D03*
X253385Y371890D03*
X263385D03*
X253385Y382520D03*
X263385D03*
X253386Y546890D03*
Y557520D03*
X263386Y546890D03*
Y557520D03*
X253386Y721890D03*
Y732520D03*
X263386Y721890D03*
Y732520D03*
X253385Y896890D03*
X263385D03*
X253385Y907520D03*
X263385D03*
X253385Y1071890D03*
X263385D03*
X253385Y1082520D03*
X263385D03*
X253385Y1246890D03*
Y1257520D03*
X263385Y1246890D03*
Y1257520D03*
X253385Y1421890D03*
Y1432520D03*
X263385Y1421890D03*
Y1432520D03*
X253385Y1596890D03*
X263385D03*
X253385Y1607520D03*
X263385D03*
X253385Y1771890D03*
X263385D03*
X253385Y1782520D03*
X263385D03*
X253385Y1946890D03*
Y1957520D03*
X263385Y1946890D03*
Y1957520D03*
X273385Y21890D03*
Y32520D03*
X283385Y21890D03*
Y32520D03*
X273385Y196890D03*
X283385D03*
X273385Y207520D03*
X283385D03*
X273385Y371890D03*
X283385D03*
X273385Y382520D03*
X283385D03*
X273386Y546890D03*
Y557520D03*
X283386Y546890D03*
Y557520D03*
X273386Y721890D03*
Y732520D03*
X283386Y721890D03*
Y732520D03*
X273385Y896890D03*
X283385D03*
X273385Y907520D03*
X283385D03*
X273385Y1071890D03*
X283385D03*
X273385Y1082520D03*
X283385D03*
X273385Y1246890D03*
Y1257520D03*
X283385Y1246890D03*
Y1257520D03*
X273385Y1421890D03*
Y1432520D03*
X283385Y1421890D03*
Y1432520D03*
X273385Y1596890D03*
X283385D03*
X273385Y1607520D03*
X283385D03*
X273385Y1771890D03*
X283385D03*
X273385Y1782520D03*
X283385D03*
X273385Y1946890D03*
Y1957520D03*
X283385Y1946890D03*
Y1957520D03*
X293385Y21890D03*
Y32520D03*
X303385Y21890D03*
Y32520D03*
X313385D03*
Y21890D03*
X293385Y196890D03*
X303385D03*
X313385D03*
X293385Y207520D03*
X303385D03*
X313385D03*
X293385Y371890D03*
X303385D03*
X313385D03*
X293385Y382520D03*
X303385D03*
X313385D03*
X293386Y546890D03*
Y557520D03*
X303386Y546890D03*
Y557520D03*
X313386D03*
Y546890D03*
X293386Y721890D03*
Y732520D03*
X303386Y721890D03*
Y732520D03*
X313386D03*
Y721890D03*
X293385Y896890D03*
X303385D03*
X313385D03*
X293385Y907520D03*
X303385D03*
X313385D03*
X293385Y1071890D03*
X303385D03*
X313385D03*
X293385Y1082520D03*
X303385D03*
X313385D03*
X293385Y1246890D03*
Y1257520D03*
X303385Y1246890D03*
Y1257520D03*
X313385D03*
Y1246890D03*
X293385Y1421890D03*
Y1432520D03*
X303385Y1421890D03*
Y1432520D03*
X313385D03*
Y1421890D03*
X293385Y1596890D03*
X303385D03*
X313385D03*
X293385Y1607520D03*
X303385D03*
X313385D03*
X293385Y1771890D03*
X303385D03*
X313385D03*
X293385Y1782520D03*
X303385D03*
X313385D03*
X293385Y1946890D03*
Y1957520D03*
X303385Y1946890D03*
Y1957520D03*
X313385D03*
Y1946890D03*
X337165Y24705D03*
X323385Y32520D03*
Y21890D03*
X337165Y34705D03*
Y199705D03*
X323385Y196890D03*
X337165Y209705D03*
X323385Y207520D03*
Y371890D03*
X337165Y374705D03*
Y384705D03*
X323385Y382520D03*
X337166Y549705D03*
Y559705D03*
X323386Y557520D03*
Y546890D03*
X337166Y724705D03*
X323386Y732520D03*
Y721890D03*
X337166Y734705D03*
X337165Y899705D03*
X323385Y896890D03*
X337165Y909705D03*
X323385Y907520D03*
Y1071890D03*
X337165Y1074705D03*
Y1084705D03*
X323385Y1082520D03*
X337165Y1249705D03*
Y1259705D03*
X323385Y1257520D03*
Y1246890D03*
X337165Y1424705D03*
Y1434705D03*
X323385Y1432520D03*
Y1421890D03*
X337165Y1599705D03*
X323385Y1596890D03*
X337165Y1609705D03*
X323385Y1607520D03*
Y1771890D03*
X337165Y1774705D03*
Y1784705D03*
X323385Y1782520D03*
X337165Y1949705D03*
Y1959705D03*
X323385Y1957520D03*
Y1946890D03*
X342165Y19705D03*
Y29705D03*
X362165Y19705D03*
Y29705D03*
X342165Y194705D03*
X362165D03*
X342165Y204705D03*
X362165D03*
X342165Y369705D03*
X362165D03*
X342165Y379705D03*
X347165Y384705D03*
X357165D03*
X362165Y379705D03*
X342166Y544705D03*
X362166D03*
Y554705D03*
X342166Y729705D03*
X362166Y719705D03*
Y729705D03*
X347166Y734705D03*
X357166D03*
X342165Y894705D03*
X357165Y899705D03*
X362165Y894705D03*
X342165Y904705D03*
X347165Y909705D03*
X357165D03*
X362165Y904705D03*
X342165Y1069705D03*
X362165D03*
X342165Y1079705D03*
X362165D03*
X342165Y1244705D03*
Y1254705D03*
X362165Y1244705D03*
Y1254705D03*
X342165Y1419705D03*
Y1429705D03*
X347165Y1434705D03*
X357165D03*
X362165Y1419705D03*
Y1429705D03*
X342165Y1594705D03*
X357165Y1599705D03*
X362165Y1594705D03*
X342165Y1604705D03*
X357165Y1609705D03*
X362165Y1604705D03*
X342165Y1769705D03*
X362165D03*
X342165Y1779705D03*
X362165D03*
X342165Y1944705D03*
Y1954705D03*
X347165Y1959705D03*
X357165D03*
X362165Y1944705D03*
Y1954705D03*
G54D59*
X119920Y28071D03*
Y218071D03*
Y228071D03*
Y238071D03*
Y248071D03*
Y258071D03*
Y268071D03*
Y278071D03*
Y288071D03*
Y298071D03*
Y308071D03*
Y1610197D03*
Y1620197D03*
Y1630197D03*
Y1640197D03*
Y1650197D03*
Y1660197D03*
Y1670197D03*
Y1680197D03*
Y1690197D03*
Y1700197D03*
Y1710197D03*
Y1958228D03*
Y1968228D03*
Y1978228D03*
Y1988228D03*
Y1998228D03*
Y2008228D03*
Y2018228D03*
Y2028228D03*
Y2038228D03*
Y2048228D03*
Y2058228D03*
X139920Y28071D03*
Y228071D03*
Y218071D03*
Y248071D03*
Y238071D03*
Y268071D03*
Y258071D03*
Y298071D03*
Y288071D03*
Y278071D03*
Y318071D03*
Y308071D03*
Y328071D03*
Y566102D03*
Y586102D03*
Y576102D03*
Y606102D03*
Y596102D03*
Y636102D03*
Y626102D03*
Y616102D03*
Y656102D03*
Y646102D03*
Y676102D03*
Y666102D03*
Y1262165D03*
Y1282165D03*
Y1272165D03*
Y1312165D03*
Y1302165D03*
Y1292165D03*
Y1332165D03*
Y1322165D03*
Y1362165D03*
Y1352165D03*
Y1342165D03*
Y1372165D03*
Y1620197D03*
Y1610197D03*
Y1650197D03*
Y1640197D03*
Y1630197D03*
Y1670197D03*
Y1660197D03*
Y1700197D03*
Y1690197D03*
Y1680197D03*
Y1720197D03*
Y1710197D03*
Y1958228D03*
Y1988228D03*
Y1978228D03*
Y1968228D03*
Y2008228D03*
Y1998228D03*
Y2038228D03*
Y2028228D03*
Y2018228D03*
Y2058228D03*
Y2048228D03*
Y2068228D03*
G54D57*
X64979Y35500D03*
Y45500D03*
X54979Y40500D03*
X64979Y65500D03*
X54979Y60500D03*
X64979Y171500D03*
X54979Y176500D03*
X64979Y181500D03*
Y201500D03*
X54979Y196500D03*
X64979Y244500D03*
X54979Y249500D03*
X64979Y254500D03*
Y264500D03*
Y274500D03*
X54979Y269500D03*
X189762Y73105D03*
X190289Y152050D03*
X190357Y247568D03*
X190817Y331786D03*
X189761Y421732D03*
X190553Y506517D03*
X192888Y598130D03*
X190816Y681645D03*
X191846Y774526D03*
X191606Y856244D03*
X196311Y947202D03*
X195516Y1032544D03*
X191250Y1122856D03*
X191342Y1206233D03*
X191846Y1299104D03*
X190552Y1380966D03*
X189463Y1474162D03*
X191079Y1557277D03*
X192143Y1648177D03*
X191607Y1731351D03*
X191530Y1823227D03*
X190289Y1900420D03*
X192125Y1998730D03*
X191530Y2043388D03*
G54D56*
X45056Y1784622D03*
Y1801158D03*
G54D48*
X30473Y102007D03*
Y137440D03*
X30197Y305027D03*
Y352271D03*
X30473Y1855008D03*
Y1890441D03*
Y1937007D03*
Y1972440D03*
Y2012007D03*
Y2047440D03*
G54D50*
X344826Y2035270D03*
X389572Y66182D03*
G54D46*
X29979Y75500D03*
Y166500D03*
Y211500D03*
Y239500D03*
Y284500D03*
Y375500D03*
Y420500D03*
G54D69*
X65354Y814960D03*
Y1514960D03*
G54D64*
X204333Y506517D03*
X204859Y1557277D03*
X205923Y1648177D03*
X205387Y1731351D03*
G54D53*
X22756Y125629D03*
Y1960629D03*
Y2035629D03*
G54D52*
X373385Y32520D03*
Y207520D03*
Y382520D03*
X373386Y557520D03*
Y732520D03*
X373385Y907520D03*
Y1082520D03*
Y1257520D03*
Y1432520D03*
Y1607520D03*
Y1957520D03*
G54D63*
X203542Y73105D03*
X204596Y681645D03*
X205122Y1206233D03*
X205310Y1823227D03*
G54D61*
X119920Y1720197D03*
G54D58*
X54979Y70500D03*
Y206500D03*
Y279500D03*
X204069Y152050D03*
X204137Y247568D03*
X204597Y331786D03*
X203541Y421732D03*
X210091Y947202D03*
X203243Y1474162D03*
X204069Y1900420D03*
X205905Y1998730D03*
G54D55*
X22756Y1878630D03*
G54D45*
X307086Y308268D03*
G54D65*
X206668Y598130D03*
X205626Y774526D03*
X205386Y856244D03*
X209296Y1032544D03*
X205030Y1122856D03*
X205626Y1299104D03*
X204332Y1380966D03*
X205310Y2043388D03*
G54D62*
X119920Y2068228D03*
G54D49*
X307087Y1343504D03*
Y1693504D03*
Y2043504D03*
G54D44*
X307086Y1883071D03*
G54D51*
X359842Y78780D03*
Y253780D03*
Y428780D03*
Y603780D03*
Y778780D03*
Y953780D03*
Y1128780D03*
Y1303780D03*
Y1478780D03*
Y1653780D03*
Y1828780D03*
Y2003780D03*
G54D47*
X65354Y114961D03*
Y464961D03*
Y1864961D03*
X307087Y127165D03*
Y477165D03*
Y827165D03*
X65354Y1164961D03*
%LPD*%
G75*
G36*
G01X65354Y95260D02*
G02I0J19700D01*
G37*
G36*
G01Y445260D02*
G02I0J19700D01*
G37*
G36*
G01Y1145260D02*
G02I0J19700D01*
G37*
G36*
G01Y1845260D02*
G02I0J19700D01*
G37*
G36*
G01X326786Y127165D02*
G02I-19700J0D01*
G37*
G36*
G01Y477165D02*
G02I-19700J0D01*
G37*
G36*
G01Y827165D02*
G02I-19700J0D01*
G37*
G36*
G01Y1343504D02*
G02I-19700J0D01*
G37*
G36*
G01Y1693504D02*
G02I-19700J0D01*
G37*
G36*
G01X326787Y2043503D02*
G02I-19700J0D01*
G37*
%LPC*%
G75*
G54D69*
X65354Y114960D03*
Y464960D03*
Y1164960D03*
Y1864960D03*
X307086Y127165D03*
Y477165D03*
Y827165D03*
Y1343504D03*
Y1693504D03*
X307087Y2043503D03*
%LPD*%
G75*
G54D10*
X29979Y30500D03*
Y75500D03*
Y166500D03*
Y211500D03*
Y239500D03*
Y284500D03*
Y375500D03*
Y420500D03*
G54D20*
X45411Y505996D03*
Y568004D03*
Y1564000D03*
Y1626008D03*
G54D11*
G01X385146Y330539D02*
X387259D01*
X389940Y333220D01*
G01X378752Y665189D02*
X375850Y668091D01*
Y672905D01*
G01X380915Y330518D02*
X385125D01*
X385146Y330539D01*
G01X378777Y1901748D02*
X374782D01*
X374431Y1901397D01*
X25219Y18752D03*
X3001Y52034D03*
Y100034D03*
Y150034D03*
Y200034D03*
Y250034D03*
Y300034D03*
Y350034D03*
Y400034D03*
Y450034D03*
Y500034D03*
X13441Y495961D03*
X3001Y550034D03*
X10914Y578848D03*
X15984Y578849D03*
X3001Y600034D03*
Y650034D03*
Y700034D03*
Y750034D03*
Y800034D03*
Y850034D03*
Y900034D03*
Y950034D03*
Y1000034D03*
Y1050034D03*
Y1100034D03*
Y1150034D03*
Y1200034D03*
Y1250034D03*
Y1300034D03*
Y1350034D03*
Y1400034D03*
Y1450034D03*
Y1500034D03*
Y1550034D03*
X11541Y1562330D03*
X3006Y1594602D03*
X3012Y1610165D03*
X3001Y1650034D03*
X11153Y1638435D03*
X16552Y1638005D03*
X3001Y1700034D03*
Y1750034D03*
Y1800034D03*
Y1850034D03*
Y1900034D03*
Y1950034D03*
Y2000034D03*
Y2050034D03*
X48433Y866179D03*
X48467Y869278D03*
X46980Y1335843D03*
X26833Y2067866D03*
X60815Y1019026D03*
X63577Y1019115D03*
X59127Y1257647D03*
X57458Y1253378D03*
X58356Y1279812D03*
X58416Y1272383D03*
X54543Y1296513D03*
X63061Y1296312D03*
X67568Y1296654D03*
X54130Y1313763D03*
X70340Y1328203D03*
X55544Y1770835D03*
X55080Y1762982D03*
X54948Y1755171D03*
X56425Y1778371D03*
X70376Y1796383D03*
X75219Y18752D03*
X97417Y32853D03*
Y37438D03*
X97536Y376580D03*
X97457Y371909D03*
X97985Y391220D03*
X97643Y396024D03*
X93223Y417736D03*
X94347Y421562D03*
X86187Y680710D03*
X79520Y682439D03*
X88681Y704108D03*
X81563Y705437D03*
X86673Y685710D03*
X79536D03*
X96308Y696622D03*
X98591Y720745D03*
X98564Y715937D03*
X97443Y739962D03*
X97534Y735248D03*
X98124Y745139D03*
X76446Y1014871D03*
X79499D03*
X96904Y1067515D03*
X96948Y1092036D03*
X96949Y1087095D03*
X96774Y1072226D03*
X97403Y1424340D03*
X97825Y1419492D03*
X96993Y1443743D03*
X96996Y1438980D03*
X97465Y1447919D03*
X95236Y1453321D03*
X88837Y1771103D03*
X91460Y1765062D03*
X93771Y1748227D03*
X80376Y1772098D03*
Y1768566D03*
X75376Y1796236D03*
X80376Y1796163D03*
X85376Y1796236D03*
X80376Y1775609D03*
X76833Y2067866D03*
X106335Y22580D03*
X108082Y38899D03*
X102646Y49461D03*
X101430Y41803D03*
X104350Y62293D03*
X107263Y72244D03*
X109054Y58250D03*
X104116Y82557D03*
X108672Y86150D03*
X105451Y406795D03*
X114498Y396207D03*
X101990Y426104D03*
X109475Y434743D03*
X111017Y419566D03*
X102960Y672823D03*
X113018Y706356D03*
X105087Y754126D03*
X101244Y774100D03*
X112836Y769122D03*
X111967Y795261D03*
X115139Y849240D03*
X105395Y972040D03*
X102611Y972220D03*
X98652Y1096403D03*
X108779Y1105760D03*
X112503Y1115860D03*
X105684Y1125919D03*
X108468Y1129286D03*
X105455Y1472894D03*
X108574Y1463389D03*
X113518Y1489571D03*
X99103Y1765722D03*
X99068Y1760827D03*
X99047Y1785571D03*
X98873Y1780542D03*
X99294Y1789947D03*
X107391Y1794460D03*
X105669Y1815227D03*
X108819Y1812118D03*
Y1824470D03*
X109991Y2083607D03*
X125219Y3002D03*
X162384Y56744D03*
X161742Y72497D03*
X162586Y68130D03*
X161339Y88108D03*
X159417Y91281D03*
X158901Y85017D03*
X169500Y126110D03*
Y118626D03*
Y111407D03*
X166500D03*
Y118626D03*
Y126110D03*
X169329Y140623D03*
X169500Y132705D03*
X169329Y148066D03*
X166329D03*
X166500Y132705D03*
X166329Y140623D03*
X169329Y156102D03*
Y163621D03*
X166329D03*
Y156102D03*
X168975Y265783D03*
X165975D03*
X168975Y296140D03*
Y286803D03*
Y276298D03*
X165975D03*
Y286803D03*
Y296140D03*
X168975Y312307D03*
Y303868D03*
X165975D03*
Y312307D03*
X161377Y407575D03*
X161517Y436119D03*
X161257Y420869D03*
X159019Y439268D03*
X158807Y432969D03*
X159430Y461714D03*
X156430D03*
X159430Y483012D03*
X159259Y490930D03*
X159430Y468933D03*
Y476417D03*
X156430D03*
Y468933D03*
X156259Y490930D03*
X156430Y483012D03*
X159259Y513928D03*
Y498373D03*
Y506409D03*
X156259D03*
Y498373D03*
Y513928D03*
X157272Y604773D03*
X160272D03*
X157272Y633416D03*
Y613574D03*
Y624079D03*
X160272D03*
Y613574D03*
Y633416D03*
X157272Y641144D03*
Y649583D03*
X160272D03*
Y641144D03*
X161826Y756757D03*
X161131Y774878D03*
X161644Y764231D03*
X158956Y780982D03*
X161479Y784141D03*
X159053Y787280D03*
X158444Y822725D03*
X165872D03*
X162872D03*
X155444D03*
X165872Y830209D03*
X158444D03*
X165872Y836804D03*
X158444D03*
X165701Y844722D03*
X158273D03*
X165701Y852165D03*
X158273D03*
X155273D03*
X162701D03*
X155273Y844722D03*
X162701D03*
X155444Y836804D03*
X162872D03*
X155444Y830209D03*
X162872D03*
X165701Y860201D03*
X158273D03*
X165701Y867720D03*
X158273D03*
X155273D03*
X162701D03*
X155273Y860201D03*
X162701D03*
X163699Y972924D03*
X166699D03*
X163699Y983439D03*
Y993944D03*
X166699D03*
Y983439D03*
X163424Y1011298D03*
Y1003570D03*
Y1019737D03*
X166424D03*
Y1003570D03*
Y1011298D03*
X164539Y1116135D03*
X162140Y1106853D03*
X159382Y1136151D03*
X158456Y1129045D03*
X156124Y1176256D03*
X163552D03*
Y1183740D03*
Y1190335D03*
X156124D03*
Y1183740D03*
X163552Y1169037D03*
X156124D03*
X153124D03*
X160552D03*
X153124Y1183740D03*
Y1190335D03*
X160552D03*
Y1183740D03*
Y1176256D03*
X153124D03*
X169375Y1183740D03*
Y1190335D03*
Y1176256D03*
X163381Y1198253D03*
X155953D03*
X152953D03*
X160381D03*
X169204D03*
X158749Y1307733D03*
X155749D03*
X158749Y1328753D03*
Y1318248D03*
X155749D03*
Y1328753D03*
X158749Y1354257D03*
Y1338090D03*
Y1345818D03*
X155749D03*
Y1338090D03*
Y1354257D03*
X163099Y1457084D03*
X162524Y1462651D03*
X162242Y1471380D03*
X159216Y1477124D03*
X154109Y1499221D03*
X161537D03*
Y1506440D03*
X170360D03*
X154109D03*
X157109D03*
X164537D03*
Y1499221D03*
X157109D03*
X159526Y1483434D03*
X153938Y1528437D03*
X154109Y1513924D03*
Y1520519D03*
X170360Y1513924D03*
Y1520519D03*
X161537D03*
Y1513924D03*
X161366Y1528437D03*
X170189D03*
X164366D03*
X164537Y1513924D03*
Y1520519D03*
X157109D03*
Y1513924D03*
X156938Y1528437D03*
X153938Y1535880D03*
Y1543916D03*
Y1551435D03*
X170189Y1535880D03*
Y1543916D03*
X161366Y1535880D03*
Y1543916D03*
Y1551435D03*
X170189D03*
X164366D03*
Y1543916D03*
Y1535880D03*
X156938Y1551435D03*
Y1543916D03*
Y1535880D03*
X161492Y1667763D03*
Y1657248D03*
X158492D03*
Y1667763D03*
X161492Y1695333D03*
Y1687605D03*
Y1678268D03*
X158492D03*
Y1687605D03*
Y1695333D03*
X161492Y1703772D03*
X158492D03*
X163250Y1815631D03*
X162140Y1807740D03*
X161844Y1828225D03*
X159822Y1831380D03*
X159075Y1825087D03*
X155091Y1866003D03*
X162519D03*
X159519D03*
X152091D03*
X155091Y1880706D03*
Y1887301D03*
X162519D03*
Y1880706D03*
Y1873222D03*
X155091D03*
X152091D03*
X168342D03*
X159519D03*
Y1880706D03*
Y1887301D03*
X168342D03*
Y1880706D03*
X152091Y1887301D03*
Y1880706D03*
X154920Y1902662D03*
Y1910698D03*
X162348Y1902662D03*
Y1910698D03*
X154920Y1895219D03*
X162348D03*
X168171D03*
X159348D03*
X151920D03*
X159348Y1910698D03*
Y1902662D03*
X168171Y1910698D03*
Y1902662D03*
X151920Y1910698D03*
Y1902662D03*
X154920Y1918217D03*
X162348D03*
X168171D03*
X159348D03*
X151920D03*
X159991Y2083607D03*
X175219Y3002D03*
X176928Y126110D03*
Y118626D03*
Y111407D03*
X173928D03*
Y118626D03*
Y126110D03*
X176757Y140623D03*
X176928Y132705D03*
X176757Y148066D03*
X173757D03*
X173928Y132705D03*
X173757Y140623D03*
X176757Y156102D03*
Y163621D03*
X173757D03*
Y156102D03*
X175033Y261594D03*
Y268813D03*
X178033D03*
Y261594D03*
X175033Y282892D03*
X174862Y290810D03*
Y298253D03*
X175033Y276297D03*
X178033D03*
X177862Y298253D03*
Y290810D03*
X178033Y282892D03*
X174862Y313808D03*
Y306289D03*
X177862D03*
Y313808D03*
X182191Y822725D03*
X174695D03*
X171695D03*
X179191D03*
X174524Y844722D03*
Y852165D03*
X182191Y830209D03*
X174695D03*
X182191Y836804D03*
X174695D03*
X182020Y844722D03*
Y852165D03*
X179020D03*
Y844722D03*
X171695Y836804D03*
X179191D03*
X171695Y830209D03*
X179191D03*
X171524Y852165D03*
Y844722D03*
X174524Y860201D03*
Y867720D03*
X182020Y860201D03*
Y867720D03*
X179020D03*
Y860201D03*
X171524Y867720D03*
Y860201D03*
X184284Y948331D03*
X184196Y967371D03*
X184632Y983423D03*
X184353Y1001556D03*
X184118Y1019280D03*
X188385Y1020810D03*
X179871Y1176256D03*
Y1190335D03*
Y1183740D03*
X172375Y1176256D03*
Y1190335D03*
Y1183740D03*
X176871D03*
Y1190335D03*
Y1176256D03*
X179700Y1198253D03*
X172204D03*
X176700D03*
X177856Y1506440D03*
X173360D03*
X180856D03*
X177856Y1513924D03*
Y1520519D03*
X177685Y1528437D03*
X173189D03*
X173360Y1520519D03*
Y1513924D03*
X180685Y1528437D03*
X180856Y1520519D03*
Y1513924D03*
X177685Y1535880D03*
Y1543916D03*
Y1551435D03*
X173189D03*
Y1543916D03*
Y1535880D03*
X180685Y1551435D03*
Y1543916D03*
Y1535880D03*
X178838Y1880706D03*
Y1887301D03*
Y1873222D03*
X171342Y1880706D03*
Y1887301D03*
Y1873222D03*
X175838D03*
Y1887301D03*
Y1880706D03*
X178667Y1902662D03*
Y1910698D03*
Y1895219D03*
X171171Y1902662D03*
Y1910698D03*
Y1895219D03*
X175667D03*
Y1910698D03*
Y1902662D03*
X178667Y1918217D03*
X171171D03*
X175667D03*
X217732Y153964D03*
Y170131D03*
Y161692D03*
Y164692D03*
Y173131D03*
Y156964D03*
X219214Y1287272D03*
Y1301975D03*
X219349Y1308924D03*
X219214Y1294491D03*
X219178Y1324285D03*
Y1332321D03*
Y1316842D03*
Y1339840D03*
X219131Y1663167D03*
Y1670386D03*
Y1684465D03*
Y1677870D03*
X218960Y1692383D03*
Y1699826D03*
Y1707862D03*
Y1715381D03*
X209991Y2083607D03*
X225219Y3002D03*
X237955Y56999D03*
X240955D03*
X237955Y64483D03*
X237784Y78996D03*
X237955Y71078D03*
X240955D03*
X240784Y78996D03*
X240955Y64483D03*
X237784Y94475D03*
Y101994D03*
Y86439D03*
X240784D03*
Y101994D03*
Y94475D03*
X238741Y153964D03*
X227700D03*
X238741Y170131D03*
Y161692D03*
X227700Y170131D03*
Y161692D03*
Y164692D03*
Y173131D03*
X238741Y164692D03*
Y173131D03*
X227700Y156964D03*
X238741D03*
X241033Y244995D03*
X233537D03*
X224714Y237776D03*
Y244995D03*
X227714D03*
Y237776D03*
X236537Y244995D03*
X241033Y259074D03*
X240862Y266992D03*
Y274435D03*
X241033Y252479D03*
X233537Y259074D03*
X233366Y266992D03*
Y274435D03*
X224714Y259074D03*
X224543Y266992D03*
Y274435D03*
X233537Y252479D03*
X224714D03*
X227714D03*
X236537D03*
X227543Y274435D03*
Y266992D03*
X227714Y259074D03*
X236366Y274435D03*
Y266992D03*
X236537Y259074D03*
X240862Y289990D03*
Y282471D03*
X233366Y289990D03*
X224543D03*
X233366Y282471D03*
X224543D03*
X227543D03*
X236366D03*
X227543Y289990D03*
X236366D03*
X239746Y407393D03*
Y396878D03*
Y417898D03*
Y399878D03*
Y410393D03*
Y420898D03*
X229548Y461083D03*
X232548D03*
X238371Y482381D03*
X238200Y490299D03*
X229548Y482381D03*
X229377Y490299D03*
X238371Y468302D03*
Y475786D03*
X229548Y468302D03*
Y475786D03*
X232548D03*
Y468302D03*
X241371Y475786D03*
Y468302D03*
X232377Y490299D03*
X232548Y482381D03*
X241200Y490299D03*
X241371Y482381D03*
X238200Y513297D03*
X229377D03*
X238200Y497742D03*
X229377D03*
X238200Y505778D03*
X229377D03*
X232377D03*
X241200D03*
X232377Y497742D03*
X241200D03*
X232377Y513297D03*
X241200D03*
X227963Y608108D03*
X235391D03*
X227963Y601513D03*
X235391D03*
Y594029D03*
X227963D03*
X230963D03*
X238391D03*
Y601513D03*
X230963D03*
X238391Y608108D03*
X230963D03*
X227792Y631505D03*
X235220D03*
X227792Y623469D03*
X235220D03*
X227792Y616026D03*
X235220D03*
X238220D03*
X230792D03*
X238220Y623469D03*
X230792D03*
X238220Y631505D03*
X230792D03*
X227792Y639024D03*
X235220D03*
X238220D03*
X230792D03*
X234012Y754782D03*
X237012D03*
X234012Y762510D03*
Y770949D03*
X237012D03*
Y762510D03*
X241396Y862887D03*
Y855159D03*
Y871326D03*
X238396D03*
Y855159D03*
Y862887D03*
X231339Y959673D03*
X238767D03*
Y967157D03*
Y973752D03*
X231339D03*
Y967157D03*
X238767Y952454D03*
X231339D03*
X234339D03*
X241767D03*
X234339Y967157D03*
Y973752D03*
X241767D03*
Y967157D03*
Y959673D03*
X234339D03*
X238596Y981670D03*
X231168D03*
X238596Y997149D03*
Y989113D03*
X231168Y997149D03*
Y989113D03*
X234168D03*
Y997149D03*
X241596Y989113D03*
Y997149D03*
X234168Y981670D03*
X241596D03*
X238596Y1004668D03*
X231168D03*
X234168D03*
X241596D03*
X235709Y1124900D03*
Y1135415D03*
X232709D03*
Y1124900D03*
X242677Y1135415D03*
Y1124900D03*
X235709Y1145920D03*
X232709D03*
X242677D03*
X235659Y1215296D03*
X228231D03*
X235659Y1207777D03*
Y1199741D03*
X228231Y1207777D03*
Y1199741D03*
X231231D03*
Y1207777D03*
X238659Y1199741D03*
Y1207777D03*
X231231Y1215296D03*
X238659D03*
X226642Y1287272D03*
X222214D03*
X229642D03*
X226642Y1301975D03*
X235465D03*
X226777Y1308924D03*
X235600D03*
X242961Y1301975D03*
X243096Y1308924D03*
X226642Y1294491D03*
X235465D03*
X242961D03*
X222214D03*
X222349Y1308924D03*
X222214Y1301975D03*
X238465Y1294491D03*
X229642D03*
X238600Y1308924D03*
X229777D03*
X238465Y1301975D03*
X229642D03*
X226606Y1324285D03*
X235429D03*
X226606Y1332321D03*
X235429D03*
X242925Y1324285D03*
Y1332321D03*
X226606Y1316842D03*
X235429D03*
X242925D03*
X222178D03*
Y1332321D03*
Y1324285D03*
X238429Y1316842D03*
X229606D03*
X238429Y1332321D03*
X229606D03*
X238429Y1324285D03*
X229606D03*
X226606Y1339840D03*
X235429D03*
X242925D03*
X222178D03*
X238429D03*
X229606D03*
X235382Y1670386D03*
X226559Y1663167D03*
Y1670386D03*
X222131D03*
X229559D03*
Y1663167D03*
X238382Y1670386D03*
X222131Y1663167D03*
X242878Y1670386D03*
X235382Y1677870D03*
X235211Y1692383D03*
X235382Y1684465D03*
X226559D03*
Y1677870D03*
X226388Y1692383D03*
X221960D03*
X222131Y1677870D03*
Y1684465D03*
X229388Y1692383D03*
X229559Y1677870D03*
Y1684465D03*
X238382D03*
X238211Y1692383D03*
X238382Y1677870D03*
X242878D03*
Y1684465D03*
X242707Y1692383D03*
X235211Y1699826D03*
X226388D03*
X235211Y1715381D03*
Y1707862D03*
X226388D03*
Y1715381D03*
X221960D03*
Y1707862D03*
X229388Y1715381D03*
Y1707862D03*
X238211D03*
Y1715381D03*
X221960Y1699826D03*
X229388D03*
X238211D03*
X242707D03*
Y1707862D03*
Y1715381D03*
X226573Y2031480D03*
X236541D03*
X226573Y2020965D03*
X236541D03*
X242582D03*
Y2031480D03*
X231541Y2020965D03*
X221573D03*
X231541Y2031480D03*
X221573D03*
X226573Y2059050D03*
X236541Y2051322D03*
Y2059050D03*
X226573Y2041985D03*
Y2051322D03*
X236541Y2041985D03*
X242582Y2059050D03*
Y2051322D03*
Y2041985D03*
X231541D03*
X221573Y2051322D03*
Y2041985D03*
X231541Y2059050D03*
Y2051322D03*
X221573Y2059050D03*
X236541Y2067489D03*
X226573D03*
X242582D03*
X221573D03*
X231541D03*
X256566Y54944D03*
X264104D03*
X256566Y45572D03*
X264104D03*
Y48572D03*
X256566D03*
X245451Y56999D03*
X248451D03*
X256566Y65449D03*
X264104D03*
Y57944D03*
X256566D03*
X264104Y68449D03*
X256566D03*
X245451Y64483D03*
X245280Y78996D03*
X245451Y71078D03*
X248451D03*
X248280Y78996D03*
X248451Y64483D03*
X245280Y94475D03*
Y101994D03*
Y86439D03*
X248280D03*
Y101994D03*
Y94475D03*
X267627Y115559D03*
X267420Y147540D03*
X256861Y153964D03*
X248083D03*
X256861Y170131D03*
Y161692D03*
X248083Y170131D03*
Y161692D03*
Y164692D03*
Y173131D03*
X256861Y164692D03*
Y173131D03*
X248083Y156964D03*
X256861D03*
X264596Y221664D03*
X252818D03*
X255818D03*
X261596D03*
X264596Y242684D03*
Y232179D03*
X252818Y242684D03*
Y232179D03*
X255818D03*
Y242684D03*
X261596Y232179D03*
Y242684D03*
X244033Y244995D03*
X264596Y268188D03*
Y259749D03*
Y252021D03*
X252818Y268188D03*
Y252021D03*
Y259749D03*
X255818D03*
Y252021D03*
Y268188D03*
X261596Y252021D03*
Y259749D03*
Y268188D03*
X244033Y252479D03*
X243862Y274435D03*
Y266992D03*
X244033Y259074D03*
X243862Y282471D03*
Y289990D03*
X266040Y407146D03*
Y396631D03*
Y417651D03*
X257572Y396630D03*
Y407145D03*
X248714Y407536D03*
Y397021D03*
X257572Y417650D03*
X248714Y418041D03*
Y400021D03*
Y410536D03*
X257572Y410145D03*
Y399630D03*
X266040Y399631D03*
Y410146D03*
X248714Y421041D03*
X257572Y420650D03*
X266040Y420651D03*
X245867Y482381D03*
X245696Y490299D03*
X245867Y468302D03*
Y475786D03*
X248867D03*
Y468302D03*
X248696Y490299D03*
X248867Y482381D03*
X245696Y513297D03*
Y497742D03*
Y505778D03*
X248696D03*
Y497742D03*
Y513297D03*
X267166Y581440D03*
Y572639D03*
X264166D03*
Y581440D03*
X267166Y609010D03*
Y601282D03*
Y591945D03*
X264166D03*
Y601282D03*
Y609010D03*
X251710Y608108D03*
Y601513D03*
Y594029D03*
X244214Y608108D03*
Y601513D03*
Y594029D03*
X247214D03*
Y601513D03*
Y608108D03*
X254710Y594029D03*
Y601513D03*
Y608108D03*
X267166Y617449D03*
X264166D03*
X264433Y624321D03*
X267433D03*
X251539Y631505D03*
Y623469D03*
Y616026D03*
X244043Y631505D03*
Y623469D03*
Y616026D03*
X247043D03*
Y623469D03*
Y631505D03*
X254539Y616026D03*
Y623469D03*
Y631505D03*
X251539Y639024D03*
X244043D03*
X247043D03*
X254539D03*
X243980Y754782D03*
X255021D03*
X258021D03*
X246980D03*
X243980Y762510D03*
Y770949D03*
X255021Y762510D03*
Y770949D03*
X258021D03*
Y762510D03*
X246980Y770949D03*
Y762510D03*
X253174Y855159D03*
Y862887D03*
Y871326D03*
X250174D03*
Y862887D03*
Y855159D03*
X265766Y949344D03*
X262766D03*
X265766Y967106D03*
Y959859D03*
X265621Y974386D03*
X262621D03*
X262766Y959859D03*
Y967106D03*
X255086Y959673D03*
Y973752D03*
Y967157D03*
X247590Y959673D03*
Y973752D03*
Y967157D03*
X250590D03*
Y973752D03*
Y959673D03*
X258086Y967157D03*
Y973752D03*
Y959673D03*
X265621Y990553D03*
Y982114D03*
X262621D03*
Y990553D03*
X254915Y981670D03*
Y997149D03*
Y989113D03*
X247419Y981670D03*
Y997149D03*
Y989113D03*
X250419D03*
Y997149D03*
Y981670D03*
X257915Y989113D03*
Y997149D03*
Y981670D03*
X254915Y1004668D03*
X247419D03*
X250419D03*
X257915D03*
X263473Y1124613D03*
Y1135128D03*
X245677Y1124900D03*
Y1135415D03*
X254433Y1135271D03*
Y1124756D03*
X251433D03*
Y1135271D03*
X260473Y1135128D03*
Y1124613D03*
X263473Y1145633D03*
X245677Y1145920D03*
X254433Y1145776D03*
X251433D03*
X260473Y1145633D03*
X267194Y1191777D03*
X251978Y1215296D03*
X244482D03*
X251978Y1207777D03*
Y1199741D03*
X244482Y1207777D03*
Y1199741D03*
X247482D03*
Y1207777D03*
X254978Y1199741D03*
Y1207777D03*
X247482Y1215296D03*
X254978D03*
X259581Y1272430D03*
Y1282945D03*
X256581D03*
Y1272430D03*
X267622D03*
Y1282945D03*
X245961Y1294491D03*
X246096Y1308924D03*
X245961Y1301975D03*
X259581Y1293450D03*
Y1302787D03*
Y1310515D03*
X256581D03*
Y1302787D03*
Y1293450D03*
X267622Y1310515D03*
Y1302787D03*
Y1293450D03*
X245925Y1316842D03*
Y1332321D03*
Y1324285D03*
X259581Y1318954D03*
X256581D03*
X267622D03*
X245925Y1339840D03*
X260939Y1548010D03*
Y1534139D03*
Y1541055D03*
X263939D03*
Y1534139D03*
Y1548010D03*
X258564Y1621823D03*
X261564D03*
X258564Y1642843D03*
Y1632338D03*
X261564D03*
Y1642843D03*
X258564Y1668347D03*
Y1659908D03*
Y1652180D03*
X261564D03*
Y1659908D03*
Y1668347D03*
X245878Y1670386D03*
X262759Y1697613D03*
Y1676593D03*
Y1687108D03*
X251718Y1697613D03*
Y1687108D03*
Y1676593D03*
X254718D03*
Y1687108D03*
X265759D03*
Y1676593D03*
X254718Y1697613D03*
X265759D03*
X245707Y1692383D03*
X245878Y1684465D03*
Y1677870D03*
X262498Y1722140D03*
X262759Y1714678D03*
Y1706950D03*
X251457Y1722140D03*
X251718Y1714678D03*
Y1706950D03*
X265759D03*
X254718D03*
Y1714678D03*
X265759D03*
X265498Y1722140D03*
X254457D03*
X245707Y1715381D03*
Y1707862D03*
Y1699826D03*
X261639Y1819074D03*
Y1812119D03*
Y1805203D03*
X253468Y1819074D03*
Y1812119D03*
Y1805203D03*
X267396Y1812122D03*
Y1805206D03*
Y1819077D03*
X250468Y1805203D03*
Y1812119D03*
Y1819074D03*
X258639Y1805203D03*
Y1812119D03*
Y1819074D03*
X261459Y1826219D03*
X253288D03*
X261459Y1840090D03*
Y1833135D03*
X253288D03*
Y1840090D03*
X250288D03*
Y1833135D03*
X267037Y1840093D03*
Y1833138D03*
X258459Y1833135D03*
Y1840090D03*
X267037Y1826222D03*
X250288Y1826219D03*
X258459D03*
X247582Y2031480D03*
Y2020965D03*
X260337D03*
Y2031480D03*
X267115Y2020965D03*
Y2031480D03*
X255337D03*
Y2020965D03*
X247582Y2041985D03*
Y2051322D03*
Y2059050D03*
X260337Y2051322D03*
Y2059050D03*
Y2041985D03*
X267115D03*
Y2059050D03*
Y2051322D03*
X255337Y2041985D03*
Y2059050D03*
Y2051322D03*
X260337Y2067489D03*
X247582D03*
X267115D03*
X255337D03*
X259991Y2083607D03*
X275219Y3002D03*
X288102Y54944D03*
Y45572D03*
X271572Y54944D03*
X279754D03*
X271572Y45572D03*
X279754D03*
Y48572D03*
X271572D03*
X288102D03*
Y65449D03*
X271572D03*
X279754D03*
Y57944D03*
X271572D03*
X288102D03*
X279754Y68449D03*
X271572D03*
X288102D03*
X276523Y147585D03*
X276617Y256400D03*
X285513Y322688D03*
X274531Y407289D03*
Y396774D03*
Y417794D03*
Y399774D03*
Y410289D03*
Y420794D03*
X286665Y432844D03*
X274991Y463099D03*
X277776Y497341D03*
X268938D03*
X289569Y532762D03*
Y516595D03*
Y524323D03*
X278944Y581440D03*
Y572639D03*
X275944D03*
Y581440D03*
X278944Y601282D03*
Y609010D03*
Y591945D03*
X275944D03*
Y609010D03*
Y601282D03*
X290984Y607215D03*
X278944Y617449D03*
X275944D03*
X276044Y624627D03*
X279044D03*
X274514Y672192D03*
X283340D03*
X278184Y782643D03*
X270070Y812192D03*
X268686Y847488D03*
X277788Y847237D03*
X277544Y949344D03*
X274544D03*
X277544Y967106D03*
Y959859D03*
X277399Y974386D03*
X274399D03*
X274544Y959859D03*
Y967106D03*
X291194Y956442D03*
X277399Y990553D03*
Y982114D03*
X274399D03*
Y990553D03*
X285666Y1016162D03*
X272821Y1124471D03*
Y1134986D03*
X269821D03*
Y1124471D03*
X288188Y1131146D03*
X272821Y1145491D03*
X269821D03*
X284182Y1184455D03*
Y1192183D03*
X287182D03*
Y1184455D03*
X276807Y1191777D03*
X284182Y1200622D03*
X287182D03*
X270622Y1282945D03*
Y1272430D03*
Y1293450D03*
Y1302787D03*
Y1310515D03*
X289210Y1305634D03*
X270622Y1318954D03*
X284240Y1374544D03*
X275052Y1374715D03*
X275521Y1479435D03*
X275400Y1548190D03*
X268534Y1548010D03*
X282995Y1548190D03*
X275400Y1534319D03*
Y1541235D03*
X268534Y1534139D03*
Y1541055D03*
X282995Y1534319D03*
Y1541235D03*
X285995D03*
Y1534319D03*
X271534Y1541055D03*
Y1534139D03*
X278400Y1541235D03*
Y1534319D03*
X285995Y1548190D03*
X271534Y1548010D03*
X278400Y1548190D03*
X270342Y1621823D03*
X273342D03*
X270342Y1642843D03*
Y1632338D03*
X273342D03*
Y1642843D03*
X270342Y1668347D03*
Y1652180D03*
Y1659908D03*
X273342D03*
Y1652180D03*
Y1668347D03*
X289421Y1656558D03*
X279703Y1723398D03*
X289499Y1723735D03*
X270396Y1819077D03*
Y1805206D03*
Y1812122D03*
X270037Y1826222D03*
Y1833138D03*
Y1840093D03*
X286623Y1829400D03*
X287121Y1898327D03*
X278262D03*
X272115Y2031480D03*
Y2020965D03*
Y2051322D03*
Y2059050D03*
Y2041985D03*
Y2067489D03*
X299687Y78778D03*
X308651D03*
X294506Y322688D03*
X300537Y516309D03*
X307966Y516419D03*
Y524147D03*
X300537Y524037D03*
Y532476D03*
X307966Y532586D03*
X292569Y524323D03*
Y516595D03*
Y532762D03*
X304966Y532586D03*
X297537Y532476D03*
Y524037D03*
X304966Y524147D03*
Y516419D03*
X297537Y516309D03*
X313791Y532871D03*
Y516704D03*
Y524432D03*
X315187Y652457D03*
X304146D03*
X307146D03*
X315187Y661258D03*
X304146D03*
Y681100D03*
X315187D03*
Y671763D03*
X304146D03*
X307146D03*
Y681100D03*
Y661258D03*
X315187Y688828D03*
X304146D03*
Y697267D03*
X315187D03*
X307146D03*
Y688828D03*
X310194Y1020657D03*
X310078Y1007303D03*
X310274Y1001286D03*
X310143Y1014094D03*
X307143D03*
X307274Y1001286D03*
X307078Y1007303D03*
X307194Y1020657D03*
X294617Y1016162D03*
X310129Y1027081D03*
X309999Y1033718D03*
X306999D03*
X307129Y1027081D03*
X309159Y1184526D03*
Y1192254D03*
X300691Y1184526D03*
X292721Y1184312D03*
Y1192040D03*
X300691Y1192254D03*
X303691D03*
X295721Y1192040D03*
Y1184312D03*
X303691Y1184526D03*
X312159Y1192254D03*
Y1184526D03*
X309159Y1200693D03*
X300691D03*
X292721Y1200479D03*
X295721D03*
X303691Y1200693D03*
X312159D03*
X312823Y1472957D03*
X312464Y1480102D03*
X312823Y1466002D03*
Y1459086D03*
X295715Y1480099D03*
X295895Y1472954D03*
X304066D03*
X303886Y1480099D03*
X295895Y1459083D03*
Y1465999D03*
X304066D03*
Y1459083D03*
X301066D03*
Y1465999D03*
X292895D03*
Y1459083D03*
X300886Y1480099D03*
X301066Y1472954D03*
X292895D03*
X292715Y1480099D03*
X309823Y1459086D03*
Y1466002D03*
X309464Y1480102D03*
X309823Y1472957D03*
X312464Y1493973D03*
Y1487018D03*
X295715Y1487015D03*
Y1493970D03*
X303886D03*
Y1487015D03*
X300886D03*
Y1493970D03*
X292715D03*
Y1487015D03*
X309464Y1487018D03*
Y1493973D03*
X313894Y1513883D03*
X304870Y1543211D03*
X295675D03*
X292614Y1864565D03*
X293606Y1858668D03*
X295754Y1917148D03*
X303349D03*
X295754Y1910232D03*
X303349D03*
X310215Y1910412D03*
X314810D03*
X307215D03*
X300349Y1910232D03*
X292754D03*
X300349Y1917148D03*
X292754D03*
X310215Y1917328D03*
X295754Y1924103D03*
X303349D03*
X310215Y1924283D03*
X307215D03*
X314810D03*
X300349Y1924103D03*
X292754D03*
X307215Y1917328D03*
X314810D03*
X309991Y2083607D03*
X325219Y3002D03*
X317567Y78778D03*
X332775Y318634D03*
X332693Y311980D03*
X329693D03*
X329775Y318634D03*
X332775Y335272D03*
Y342461D03*
Y325935D03*
X329775D03*
Y342461D03*
Y335272D03*
X332685Y348655D03*
X329685D03*
X325139Y516632D03*
Y524360D03*
X316791Y524432D03*
Y516704D03*
Y532871D03*
X325139Y532799D03*
X322139D03*
Y524360D03*
Y516632D03*
X318187Y652457D03*
Y671763D03*
Y681100D03*
Y661258D03*
Y697267D03*
Y688828D03*
X321235Y1020657D03*
X321315Y1001286D03*
X321119Y1007303D03*
X321184Y1014094D03*
X318184D03*
X318119Y1007303D03*
X318315Y1001286D03*
X318235Y1020657D03*
X321170Y1027081D03*
X321040Y1033718D03*
X318040D03*
X318170Y1027081D03*
X325796Y1162266D03*
X317936Y1192253D03*
Y1184525D03*
X320936D03*
Y1192253D03*
X323403Y1172804D03*
X317936Y1200692D03*
X320936D03*
X317810Y1910412D03*
Y1917328D03*
Y1924283D03*
X320045Y2005215D03*
X343816Y318634D03*
X343734Y311980D03*
X340734D03*
X340816Y318634D03*
X361799Y311938D03*
X343816Y335272D03*
Y342461D03*
Y325935D03*
X340816D03*
Y342461D03*
Y335272D03*
X362236Y324983D03*
X343726Y348655D03*
X340726D03*
X354000Y652170D03*
X356559Y675167D03*
X363169Y1329686D03*
X351391D03*
X354391D03*
X363169Y1350706D03*
Y1360043D03*
Y1340201D03*
X351391Y1350706D03*
Y1360043D03*
Y1340201D03*
X354391D03*
Y1360043D03*
Y1350706D03*
X363169Y1376210D03*
Y1367771D03*
X351391Y1376210D03*
Y1367771D03*
X354391D03*
Y1376210D03*
X352337Y1887285D03*
X359991Y2083607D03*
X375219Y3002D03*
X366169Y1329686D03*
Y1340201D03*
Y1360043D03*
Y1350706D03*
X373564Y1352548D03*
X366169Y1367771D03*
Y1376210D03*
X374681Y1365620D03*
X366306Y1899864D03*
X402512Y17108D03*
Y67108D03*
Y117108D03*
Y167108D03*
Y217108D03*
Y267108D03*
Y317108D03*
Y367108D03*
Y417108D03*
Y467108D03*
Y517108D03*
Y567108D03*
Y617108D03*
Y667108D03*
Y717108D03*
Y767108D03*
Y817108D03*
Y867108D03*
Y917108D03*
Y967108D03*
Y1017108D03*
Y1067108D03*
Y1117108D03*
Y1167108D03*
Y1217108D03*
Y1267108D03*
Y1317108D03*
Y1367108D03*
Y1417108D03*
Y1467108D03*
Y1517108D03*
Y1567108D03*
Y1617108D03*
Y1667108D03*
Y1717108D03*
Y1767108D03*
Y1817108D03*
Y1867108D03*
Y1917108D03*
Y1967108D03*
Y2017108D03*
Y2067108D03*
G54D30*
X119920Y328071D03*
Y676102D03*
Y1024134D03*
Y1372165D03*
Y1720197D03*
Y2068228D03*
G54D12*
X22756Y113818D03*
X22480Y316838D03*
Y328649D03*
X22756Y1866819D03*
Y1948818D03*
Y2023818D03*
G54D21*
G01X189762Y69353D02*
Y73105D01*
G01D02*
Y76857D01*
G01X186010Y73105D02*
X189762D01*
G01D02*
X193514D01*
G01X190289Y148298D02*
Y152050D01*
G01D02*
Y155802D01*
G01X186537Y152050D02*
X190289D01*
G01D02*
X194041D01*
G01X190357Y243816D02*
Y247568D01*
G01D02*
Y251320D01*
G01X186605Y247568D02*
X190357D01*
G01D02*
X194109D01*
G01X190817Y328034D02*
Y331786D01*
G01D02*
Y335538D01*
G01X187065Y331786D02*
X190817D01*
G01D02*
X194569D01*
G01X189761Y417980D02*
Y421732D01*
G01D02*
Y425484D01*
G01X186009Y421732D02*
X189761D01*
G01D02*
X193513D01*
G01X190553Y502765D02*
Y506517D01*
G01D02*
Y510269D01*
G01X186801Y506517D02*
X190553D01*
G01D02*
X194305D01*
G01X192888Y594378D02*
Y598130D01*
G01D02*
Y601882D01*
G01X189136Y598130D02*
X192888D01*
G01D02*
X196640D01*
G01X190816Y677893D02*
Y681645D01*
G01D02*
Y685397D01*
G01X187064Y681645D02*
X190816D01*
G01D02*
X194568D01*
G01X191846Y770774D02*
Y774526D01*
G01D02*
Y778278D01*
G01X188094Y774526D02*
X191846D01*
G01D02*
X195598D01*
G01X191606Y852492D02*
Y856244D01*
G01D02*
Y859996D01*
G01X187854Y856244D02*
X191606D01*
G01D02*
X195358D01*
G01X192559Y947202D02*
X196311D01*
G01X191764Y1032544D02*
X195516D01*
G01X191250Y1119104D02*
Y1122856D01*
G01D02*
Y1126608D01*
G01X187498Y1122856D02*
X191250D01*
G01D02*
X195002D01*
G01X191342Y1202481D02*
Y1206233D01*
G01D02*
Y1209985D01*
G01X187590Y1206233D02*
X191342D01*
G01D02*
X195094D01*
G01X191846Y1295352D02*
Y1299104D01*
G01D02*
Y1302856D01*
G01X188094Y1299104D02*
X191846D01*
G01D02*
X195598D01*
G01X190552Y1377214D02*
Y1380966D01*
G01D02*
Y1384718D01*
G01X186800Y1380966D02*
X190552D01*
G01D02*
X194304D01*
G01X189463Y1470410D02*
Y1474162D01*
G01D02*
Y1477914D01*
G01X185711Y1474162D02*
X189463D01*
G01D02*
X193215D01*
G01X191079Y1553525D02*
Y1557277D01*
G01D02*
Y1561029D01*
G01X187327Y1557277D02*
X191079D01*
G01D02*
X194831D01*
G01X192143Y1644425D02*
Y1648177D01*
G01D02*
Y1651929D01*
G01X188391Y1648177D02*
X192143D01*
G01D02*
X195895D01*
G01X191607Y1727599D02*
Y1731351D01*
G01D02*
Y1735103D01*
G01X187855Y1731351D02*
X191607D01*
G01D02*
X195359D01*
G01X191530Y1819475D02*
Y1823227D01*
G01D02*
Y1826979D01*
G01X187778Y1823227D02*
X191530D01*
G01D02*
X195282D01*
G01X190289Y1896668D02*
Y1900420D01*
G01D02*
Y1904172D01*
G01X186537Y1900420D02*
X190289D01*
G01D02*
X194041D01*
G01X192125Y1994978D02*
Y1998730D01*
G01D02*
Y2002482D01*
G01X188373Y1998730D02*
X192125D01*
G01D02*
X195877D01*
G01X191530Y2039636D02*
Y2043388D01*
G01D02*
Y2047140D01*
G01X187778Y2043388D02*
X191530D01*
G01D02*
X195282D01*
G01X196311Y943450D02*
Y947202D01*
G01D02*
Y950954D01*
G01Y947202D02*
X200063D01*
G01X195516Y1028792D02*
Y1032544D01*
G01D02*
Y1036296D01*
G01Y1032544D02*
X199268D01*
X49441Y1238962D03*
X45581Y1278420D03*
X45413Y1283724D03*
X45244Y1289067D03*
X45350Y1299697D03*
X45267Y1294203D03*
X45281Y1310893D03*
X45244Y1305787D03*
X46980Y1325843D03*
Y1315843D03*
Y1320843D03*
Y1330843D03*
Y1345843D03*
Y1340843D03*
X61888Y666012D03*
X57124Y675327D03*
X54483Y679810D03*
X59236Y670758D03*
X70865Y872278D03*
Y866278D03*
Y860278D03*
Y897750D03*
Y890116D03*
X61866Y1309190D03*
X54543Y1308995D03*
X67568Y1307829D03*
X61866Y1342104D03*
X95775Y751469D03*
X89338Y878294D03*
X91733Y899382D03*
X92633Y907404D03*
X91294Y926951D03*
X98139Y990959D03*
X82763Y1060051D03*
X96684Y1081791D03*
X96510Y1395382D03*
X106958Y26285D03*
X107405Y49898D03*
X107037Y34687D03*
X106836Y376461D03*
X106709Y391219D03*
X107025Y725368D03*
X106935Y745139D03*
X107173Y735219D03*
X100687Y999391D03*
X107351Y1093484D03*
X107235Y1081791D03*
X107215Y1072208D03*
X105152Y1118381D03*
X100719Y1312810D03*
Y1306810D03*
Y1330810D03*
Y1336810D03*
Y1324810D03*
Y1318810D03*
Y1346065D03*
X106962Y1434041D03*
X106921Y1419492D03*
X106763Y1444599D03*
X107006Y1452651D03*
X107355Y1770437D03*
X107220Y1791589D03*
X107373Y1780544D03*
X106819Y1802230D03*
X144878Y1738861D03*
X157558Y51426D03*
X156865Y401207D03*
X156610Y751063D03*
X156854Y1101031D03*
X158618Y1399448D03*
X164037Y1400226D03*
X170351Y1401324D03*
X159192Y1451105D03*
X163257Y1737619D03*
X150309Y1737009D03*
X168151Y1739208D03*
X165782Y1732903D03*
X156183Y1735240D03*
X156452Y1800821D03*
X175989Y944537D03*
X176011Y936829D03*
X175359Y963486D03*
X175561Y955964D03*
X175135Y972490D03*
X175022Y980281D03*
X175742Y989958D03*
X175449Y997660D03*
X175698Y1008730D03*
X175473Y1016296D03*
X175448Y1031766D03*
X175897Y1023997D03*
X176083Y1402321D03*
X173394Y1736051D03*
X256947Y128276D03*
X257125Y115559D03*
X263086Y147675D03*
X265722Y463102D03*
X265737Y473680D03*
X264516Y497341D03*
X255837Y823626D03*
X255687Y812192D03*
X264181Y847354D03*
X262559Y1191777D03*
X271943Y147630D03*
X271547Y260353D03*
X281193Y256624D03*
X281074Y322688D03*
X289895D03*
X281569Y436169D03*
X291002Y432844D03*
X273405Y497341D03*
X285348Y610540D03*
X270109Y672192D03*
X278955D03*
X273114Y785968D03*
X282737Y782643D03*
X273305Y847237D03*
X285966Y959767D03*
X281124Y1016162D03*
X290107D03*
X282958Y1134471D03*
X272082Y1191777D03*
X283808Y1308959D03*
X279518Y1374543D03*
X270579Y1374626D03*
X279990Y1479435D03*
X270234Y1482760D03*
X291054Y1543211D03*
X284086Y1659883D03*
X284583Y1723465D03*
X274704Y1723196D03*
X281066Y1834569D03*
X291550Y1829846D03*
X280240Y1858668D03*
X279976Y1864565D03*
X282717Y1898327D03*
X273817D03*
X304151Y78778D03*
X313089D03*
X294483Y82732D03*
X308057Y248863D03*
X306267Y241010D03*
X314914Y238162D03*
X314940Y252083D03*
X295509Y607215D03*
X295874Y956442D03*
X309678Y1053262D03*
X292698Y1131146D03*
X312527Y1162266D03*
X312698Y1172804D03*
X294133Y1305634D03*
X314183Y1403423D03*
X302267Y1524401D03*
X301734Y1513883D03*
X300392Y1543211D03*
X312077Y1575871D03*
X294090Y1656558D03*
X314562Y2009087D03*
X331403Y51409D03*
X333889Y56021D03*
X338227Y61559D03*
X322005Y78778D03*
X320372Y225979D03*
X318088Y231820D03*
X321899Y238137D03*
X331046Y232021D03*
X320961Y250105D03*
X324709Y231580D03*
X335522Y404033D03*
X323313Y418313D03*
X326196Y413982D03*
X328950Y409216D03*
X320980Y423225D03*
X336617Y577978D03*
X319305Y582111D03*
X329636Y584715D03*
X317724Y588250D03*
X337387Y586230D03*
X320380Y576491D03*
X331867Y589810D03*
X333750Y595326D03*
X321742Y599041D03*
X331568Y752967D03*
X339012Y752859D03*
X329336Y762693D03*
X334010Y758588D03*
X327524Y758020D03*
X329938Y948756D03*
X332527Y943746D03*
X324098Y946104D03*
X318557Y941178D03*
X323868Y929978D03*
X326646Y939788D03*
X336160Y937262D03*
X328583Y933262D03*
X321425Y951577D03*
X324246Y1051786D03*
X335677Y1048904D03*
X317592Y1053050D03*
X337509Y1109598D03*
X328989Y1121090D03*
X326558Y1126368D03*
X327452Y1279447D03*
X321978Y1282086D03*
X329619Y1284016D03*
X327932Y1289221D03*
X325636Y1399114D03*
X334646Y1400804D03*
X323720Y1570924D03*
X333474Y1566686D03*
X335963Y1573797D03*
X323813Y1753231D03*
X329887Y1752081D03*
X332399Y1926787D03*
X324803Y2005272D03*
X359931Y52189D03*
X348289Y50863D03*
X345089Y56190D03*
X340373Y51579D03*
X362227Y299380D03*
X356831Y299956D03*
X360533Y339095D03*
X342097Y401684D03*
X363825Y401768D03*
X342900Y580126D03*
X364353Y650514D03*
X358911Y650530D03*
X347227Y694078D03*
X352358Y698363D03*
X362531Y694417D03*
X362577Y752783D03*
X344109Y751809D03*
X343656Y933725D03*
X345578Y1047844D03*
X344099Y1106798D03*
X344130Y1401670D03*
X350690Y1403243D03*
X348710Y1570187D03*
X361011Y1568890D03*
X343402Y1572080D03*
X348245Y1575241D03*
X355364Y1570990D03*
X361039Y1875684D03*
X353250Y1874308D03*
X347105Y1875191D03*
X345537Y1916558D03*
X344402Y1911123D03*
X353726Y1914205D03*
X360118Y1912411D03*
X363361Y1918313D03*
X358318Y1920680D03*
X363411Y1923459D03*
X340336Y1922409D03*
X372204Y56126D03*
X379257Y52158D03*
X387524Y76847D03*
X373942Y300523D03*
X368544Y300470D03*
X367076Y340100D03*
X374442Y406857D03*
X374542Y401282D03*
X368907Y404308D03*
X368680Y694668D03*
X376654Y754748D03*
X382892Y767710D03*
X386790Y774338D03*
X379335Y1189778D03*
X383276Y1184136D03*
X386816Y1179841D03*
X376472Y1194999D03*
X373674Y1199967D03*
X371523Y1204725D03*
X385261Y1334686D03*
X378904Y1333844D03*
X381725Y1340790D03*
X373499Y1340730D03*
X377984Y1383142D03*
X380378Y1377228D03*
X367829Y1566108D03*
X365922Y1870477D03*
X374431Y1901397D03*
X374775Y1919243D03*
X379403Y1917261D03*
X369748Y1921795D03*
G54D40*
G01X359677Y306891D02*
Y309816D01*
X361799Y311938D01*
G01X354000Y656986D02*
Y652170D01*
G01X351983Y1882006D02*
Y1886931D01*
X352337Y1887285D01*
G01X380915Y330518D02*
X380710Y330313D01*
Y328206D01*
X379126Y326622D01*
X376347D01*
X375031Y327938D01*
Y329891D01*
G01X375850Y672905D02*
X371371D01*
X369354Y674922D01*
Y679986D01*
G01D02*
Y687681D01*
X369676Y688003D01*
G01X391395Y1362340D02*
X387476Y1366259D01*
Y1370255D01*
G01X372122Y1347255D02*
Y1351106D01*
X373564Y1352548D01*
G01X388017Y1382366D02*
Y1377774D01*
G01D02*
X387476Y1377233D01*
Y1370255D01*
G01X374431Y1901397D02*
X368633D01*
X367337Y1902693D01*
Y1905006D01*
G54D22*
X45056Y1817693D03*
G54D31*
X163385Y27205D03*
Y202205D03*
Y377205D03*
X163386Y552205D03*
Y727205D03*
X163385Y902205D03*
Y1077205D03*
Y1252205D03*
Y1427205D03*
Y1602205D03*
Y1777205D03*
Y1952205D03*
X373385Y32520D03*
Y207520D03*
Y382520D03*
X373386Y557520D03*
Y732520D03*
X373385Y907520D03*
Y1082520D03*
Y1257520D03*
Y1432520D03*
Y1607520D03*
Y1782520D03*
Y1957520D03*
G54D13*
X22756Y125629D03*
X22480Y340460D03*
X22756Y1878630D03*
Y1960629D03*
Y2035629D03*
G54D41*
G01X60815Y1019026D02*
Y1084081D01*
X81152Y1104418D01*
Y1121661D01*
X96985Y1137494D01*
Y1252147D01*
X79344Y1269788D01*
Y1411288D01*
X86507Y1418451D01*
Y1493650D01*
X95146Y1502289D01*
Y1738856D01*
X99925Y1743635D01*
Y1755277D01*
X95903Y1759299D01*
Y1818605D01*
X110828Y1833530D01*
X147562D01*
X149712Y1831380D01*
X159822D01*
G01X108819Y1824470D02*
X102559Y1818210D01*
Y1741051D01*
X97746Y1736238D01*
Y1500982D01*
X89269Y1492505D01*
Y1417306D01*
X82106Y1410143D01*
Y1270933D01*
X99747Y1253292D01*
Y1136349D01*
X83914Y1120516D01*
Y1103273D01*
X63577Y1082936D01*
Y1019115D01*
G01X113018Y706356D02*
X103284Y696622D01*
X96308D01*
G01X159382Y1136151D02*
X150261Y1127030D01*
X115578D01*
X109643Y1132965D01*
X105328D01*
X90731Y1118368D01*
Y1100633D01*
X76446Y1086348D01*
Y1014871D01*
G01X108468Y1129286D02*
X105523D01*
X93376Y1117139D01*
Y1098960D01*
X79499Y1085083D01*
Y1014871D01*
G01X108672Y86150D02*
Y92316D01*
X105231Y95757D01*
Y331673D01*
X128254Y354696D01*
X139732D01*
X149634Y364598D01*
Y381843D01*
X165000Y397209D01*
Y438547D01*
X152271Y451276D01*
X114773D01*
X108160Y457889D01*
Y677675D01*
X132220Y701735D01*
X145652D01*
X152883Y708966D01*
Y732494D01*
X173995Y753606D01*
Y794103D01*
X145887Y822211D01*
Y826271D01*
X142893Y829265D01*
X117608D01*
X109633Y837240D01*
Y931372D01*
X117293Y939032D01*
X147070D01*
X150455Y942417D01*
X173869D01*
X175989Y944537D01*
G01X159417Y91281D02*
X157559Y93139D01*
X113720D01*
X107831Y99028D01*
Y330595D01*
X129068Y351832D01*
X140839D01*
X152234Y363227D01*
Y380392D01*
X167864Y396022D01*
Y440528D01*
X147315Y461077D01*
X116821D01*
X111501Y466397D01*
Y676291D01*
X133006Y697796D01*
X146360D01*
X155802Y707238D01*
Y730754D01*
X177289Y752241D01*
Y795468D01*
X149826Y822931D01*
Y832652D01*
X143526Y838952D01*
X117922D01*
X112250Y844624D01*
Y923316D01*
X118237Y929303D01*
X144310D01*
X154130Y939123D01*
X173717D01*
X176011Y936829D01*
G01X119920Y88071D02*
X115298Y83449D01*
X107423D01*
X102631Y88241D01*
Y332750D01*
X129297Y359416D01*
X140121D01*
X147034Y366329D01*
Y428962D01*
X144760Y431236D01*
X124786D01*
X119920Y436102D01*
G01X109475Y434743D02*
X100360Y443858D01*
Y679463D01*
X129426Y708529D01*
X142633D01*
X146386Y712282D01*
Y735259D01*
X166489Y755362D01*
Y791181D01*
X148493Y809177D01*
X115243D01*
X104433Y819987D01*
Y947402D01*
X116031Y959000D01*
X149273D01*
X151627Y961354D01*
X173227D01*
X175359Y963486D01*
G01X159019Y439268D02*
X157585Y440702D01*
X118814D01*
X105560Y453956D01*
Y679919D01*
X130487Y704846D01*
X144311D01*
X149583Y710118D01*
Y733247D01*
X170172Y753836D01*
Y792707D01*
X143462Y819417D01*
X114929D01*
X107033Y827313D01*
Y938854D01*
X117648Y949469D01*
X144704D01*
X152906Y957671D01*
X173854D01*
X175561Y955964D01*
G01X102960Y672823D02*
Y450375D01*
X117233Y436102D01*
X119920D01*
G01X159053Y787280D02*
X147092Y799241D01*
X117816D01*
X101833Y815224D01*
Y967409D01*
X105395Y970971D01*
Y972040D01*
G01X111967Y795261D02*
X99233Y807995D01*
Y968842D01*
X102611Y972220D01*
G01X115139Y849240D02*
Y917551D01*
X116822Y919234D01*
X148125D01*
X156609Y927718D01*
X175041D01*
X181113Y933790D01*
Y963484D01*
X177675Y966922D01*
X155732D01*
X148053Y974601D01*
Y1088119D01*
X167737Y1107803D01*
Y1132149D01*
X158958Y1140928D01*
X148428D01*
X144988Y1137488D01*
X135107D01*
X129784Y1132165D01*
X119920D01*
G01D02*
X108803Y1143282D01*
Y1381965D01*
X127986Y1401148D01*
X146779D01*
X149589Y1403958D01*
Y1468965D01*
X143665Y1474889D01*
X135547D01*
X130239Y1480197D01*
X119920D01*
G01X175448Y1031766D02*
X173134Y1029452D01*
X160796D01*
X153758Y1036490D01*
Y1084936D01*
X173813Y1104991D01*
Y1134551D01*
X151333Y1157031D01*
X117645D01*
X115067Y1159609D01*
Y1379586D01*
X130646Y1395165D01*
X150542D01*
X155490Y1400113D01*
Y1479398D01*
X159526Y1483434D01*
G01X113518Y1489571D02*
X118102Y1484987D01*
X142533D01*
X152438Y1475082D01*
Y1402575D01*
X147880Y1398017D01*
X129109D01*
X112226Y1381134D01*
Y1152644D01*
X117686Y1147184D01*
X156863D01*
X170761Y1133286D01*
Y1106256D01*
X150706Y1086201D01*
Y1035225D01*
X159531Y1026400D01*
X173494D01*
X175897Y1023997D01*
G01X119920Y1828228D02*
X127654D01*
X132766Y1823116D01*
X142860D01*
X150613Y1815363D01*
Y1758458D01*
X142640Y1750485D01*
X134814D01*
X109727Y1725398D01*
Y1487433D01*
X116963Y1480197D01*
X119920D01*
G54D32*
X173385Y32520D03*
Y207520D03*
Y382520D03*
X173386Y557520D03*
Y732520D03*
X173385Y907520D03*
Y1082520D03*
Y1257520D03*
Y1432520D03*
Y1607520D03*
Y1782520D03*
Y1957520D03*
G54D23*
X64979Y35500D03*
Y45500D03*
Y55500D03*
X54979Y40500D03*
Y50500D03*
X64979Y65500D03*
X54979Y60500D03*
X64979Y171500D03*
X54979Y176500D03*
X64979Y181500D03*
Y191500D03*
Y201500D03*
X54979Y186500D03*
Y196500D03*
X64979Y244500D03*
X54979Y249500D03*
X64979Y254500D03*
Y264500D03*
Y274500D03*
X54979Y259500D03*
Y269500D03*
X64979Y380500D03*
Y390500D03*
X54979Y385500D03*
Y395500D03*
X64979Y400500D03*
Y410500D03*
X54979Y405500D03*
X189762Y73105D03*
X190289Y152050D03*
X190357Y247568D03*
X190817Y331786D03*
X189761Y421732D03*
X190553Y506517D03*
X192888Y598130D03*
X190816Y681645D03*
X191846Y774526D03*
X191606Y856244D03*
X196311Y947202D03*
X195516Y1032544D03*
X191250Y1122856D03*
X191342Y1206233D03*
X191846Y1299104D03*
X190552Y1380966D03*
X189463Y1474162D03*
X191079Y1557277D03*
X192143Y1648177D03*
X191607Y1731351D03*
X191530Y1823227D03*
X190289Y1900420D03*
X192125Y1998730D03*
X191530Y2043388D03*
G54D14*
X14073Y512197D03*
Y522000D03*
Y552000D03*
Y561803D03*
Y1580004D03*
Y1570201D03*
Y1610004D03*
Y1619807D03*
X30473Y102007D03*
Y137440D03*
X30197Y305027D03*
Y352271D03*
X30473Y1855008D03*
Y1890441D03*
Y1937007D03*
Y1972440D03*
Y2012007D03*
Y2047440D03*
X65254Y519500D03*
Y529500D03*
Y539500D03*
X55254Y524500D03*
Y534500D03*
X65254Y549500D03*
X55254Y544500D03*
X65254Y1577504D03*
Y1587504D03*
Y1597504D03*
X55254Y1582504D03*
Y1592504D03*
Y1602504D03*
X65254Y1607504D03*
G54D42*
G01Y519500D02*
X60113D01*
X56702Y516089D01*
X44328D01*
X18902Y541515D01*
Y595231D01*
X25755Y602084D01*
Y689382D01*
X27561Y691188D01*
Y698999D01*
X18925Y707635D01*
Y716291D01*
X16786Y718430D01*
X12765D01*
X10616Y720579D01*
Y725383D01*
X11461Y726228D01*
Y727795D01*
X11238Y728240D01*
X11236Y728241D01*
X10565Y728466D01*
X7673Y727049D01*
G01X55254Y524500D02*
X58262Y521492D01*
Y519912D01*
X56039Y517689D01*
X44991D01*
X41609Y521071D01*
Y521973D01*
X40549Y523033D01*
X39647D01*
X38587Y524093D01*
Y524995D01*
X37527Y526055D01*
X36625D01*
X35565Y527115D01*
Y528017D01*
X34505Y529077D01*
X33603D01*
X32543Y530137D01*
Y531039D01*
X31483Y532099D01*
X30581D01*
X29521Y533159D01*
Y534061D01*
X28461Y535121D01*
X27559D01*
X20502Y542178D01*
Y594568D01*
X27355Y601421D01*
Y688719D01*
X29161Y690525D01*
Y699662D01*
X20525Y708298D01*
Y716954D01*
X17449Y720030D01*
X13428D01*
X12216Y721242D01*
Y724720D01*
X13061Y725565D01*
Y728173D01*
X12670Y728955D01*
X12893Y729626D01*
X15547Y730986D01*
G01X55254Y534500D02*
X59089Y536420D01*
X59760Y536195D01*
X59985Y535746D01*
X60102Y535513D01*
X62259Y533357D01*
X69291D01*
X71831Y535897D01*
Y541611D01*
X67529Y545913D01*
X60844D01*
X56702Y550055D01*
X53068D01*
X51361Y551762D01*
Y562159D01*
X53336Y564134D01*
Y572911D01*
X40960Y585287D01*
Y617693D01*
X43475Y620208D01*
Y733938D01*
X37823Y739590D01*
X31153D01*
X26991Y735428D01*
X14317D01*
X11578Y738167D01*
Y739159D01*
X11762Y739343D01*
X11878Y739575D01*
X11879D01*
X12104Y740023D01*
X12775Y740248D01*
X15547Y738860D01*
G01X65254Y539500D02*
X61417Y537578D01*
X61194Y536907D01*
X61417Y536462D01*
X62922Y534957D01*
X68628D01*
X70231Y536560D01*
Y540948D01*
X66866Y544313D01*
X60181D01*
X56039Y548455D01*
X52405D01*
X49761Y551099D01*
Y562822D01*
X51736Y564797D01*
Y572248D01*
X39360Y584624D01*
Y618356D01*
X41875Y620871D01*
Y624781D01*
X41197Y625459D01*
Y626959D01*
X41875Y627637D01*
Y629137D01*
X41197Y629815D01*
Y631315D01*
X41875Y631993D01*
Y633493D01*
X41197Y634171D01*
Y635671D01*
X41875Y636349D01*
Y637849D01*
X41197Y638527D01*
Y640027D01*
X41875Y640705D01*
Y642205D01*
X41197Y642883D01*
Y644383D01*
X41875Y645061D01*
Y646561D01*
X41197Y647239D01*
Y648739D01*
X41875Y649417D01*
Y650917D01*
X41197Y651595D01*
Y653095D01*
X41875Y653773D01*
Y733275D01*
X37160Y737990D01*
X31816D01*
X27654Y733828D01*
X13654D01*
X9978Y737504D01*
Y739822D01*
X10447Y740291D01*
X10670Y740737D01*
X10447Y741408D01*
X7673Y742797D01*
G01X15551Y1380590D02*
X12779Y1381978D01*
X12108Y1381753D01*
X11883Y1381305D01*
X11882D01*
X11766Y1381073D01*
X11582Y1380889D01*
Y1379747D01*
X13629Y1377700D01*
X17877D01*
X19845Y1379668D01*
Y1590678D01*
X49014Y1619847D01*
X58971D01*
X63310Y1615508D01*
Y1612829D01*
X62385Y1611904D01*
Y1610372D01*
X65254Y1607504D01*
G01X7677Y1384527D02*
X10451Y1383138D01*
X10674Y1382467D01*
X10451Y1382021D01*
X9982Y1381552D01*
Y1379084D01*
X12966Y1376100D01*
X18540D01*
X21445Y1379005D01*
Y1590015D01*
X49677Y1618247D01*
X58308D01*
X61710Y1614845D01*
Y1613492D01*
X60722Y1612504D01*
X55254D01*
G01X15551Y1372716D02*
X12779Y1371328D01*
X12556Y1370657D01*
X12664Y1370441D01*
X13585Y1369520D01*
X26373D01*
X30242Y1373389D01*
X34351D01*
X36813Y1375851D01*
Y1387831D01*
X36087Y1388557D01*
Y1390057D01*
X36813Y1390783D01*
Y1392283D01*
X36087Y1393009D01*
Y1394509D01*
X36813Y1395235D01*
Y1396735D01*
X36087Y1397461D01*
Y1398961D01*
X36813Y1399687D01*
Y1401187D01*
X36087Y1401913D01*
Y1403413D01*
X36813Y1404139D01*
Y1405639D01*
X36087Y1406365D01*
Y1407865D01*
X36813Y1408591D01*
Y1411545D01*
X32808Y1415550D01*
Y1536105D01*
X51582Y1554879D01*
Y1573460D01*
X49452Y1575590D01*
Y1587327D01*
X51762Y1589638D01*
Y1599012D01*
X55254Y1602504D01*
G01X7677Y1368779D02*
X10451Y1370168D01*
X11122Y1369943D01*
X11347Y1369495D01*
X12922Y1367920D01*
X27036D01*
X30905Y1371789D01*
X35014D01*
X38413Y1375188D01*
Y1412208D01*
X34408Y1416213D01*
Y1535442D01*
X53182Y1554216D01*
Y1574123D01*
X51052Y1576253D01*
Y1586663D01*
X53314Y1588925D01*
X63833D01*
X65254Y1587504D01*
G01Y529500D02*
X54699D01*
X50629Y533570D01*
X45208D01*
X41010Y537768D01*
Y561927D01*
X30932Y572005D01*
Y646825D01*
X32369Y648262D01*
X33671D01*
X34171Y648762D01*
Y651862D01*
X33671Y652362D01*
X32369D01*
X30932Y653799D01*
Y658225D01*
X32369Y659662D01*
X33671D01*
X34171Y660162D01*
Y663262D01*
X33671Y663762D01*
X32369D01*
X30932Y665199D01*
Y669625D01*
X32369Y671062D01*
X33671D01*
X34171Y671562D01*
Y674662D01*
X33671Y675162D01*
X32369D01*
X30932Y676599D01*
Y684739D01*
X36637Y690444D01*
Y729110D01*
X35501Y730246D01*
X31180D01*
X30489Y729555D01*
X30266Y729109D01*
X30489Y728438D01*
X33263Y727049D01*
G01X55254Y544500D02*
Y539649D01*
X50775Y535170D01*
X45871D01*
X42610Y538431D01*
Y542399D01*
X43312Y543101D01*
Y544601D01*
X42610Y545303D01*
Y546803D01*
X43312Y547505D01*
Y549005D01*
X42610Y549707D01*
Y551207D01*
X43312Y551909D01*
Y553409D01*
X42610Y554111D01*
Y562590D01*
X32532Y572668D01*
Y646162D01*
X33032Y646662D01*
X34334D01*
X35771Y648099D01*
Y652525D01*
X34334Y653962D01*
X33032D01*
X32532Y654462D01*
Y657562D01*
X33032Y658062D01*
X34334D01*
X35771Y659499D01*
Y663925D01*
X34334Y665362D01*
X33032D01*
X32532Y665862D01*
Y668962D01*
X33032Y669462D01*
X34334D01*
X35771Y670899D01*
Y675325D01*
X34334Y676762D01*
X33032D01*
X32532Y677262D01*
Y684076D01*
X38237Y689781D01*
Y729773D01*
X36164Y731846D01*
X30517D01*
X29174Y730503D01*
X29058Y730271D01*
X29057D01*
X28832Y729823D01*
X28161Y729598D01*
X25389Y730986D01*
G01Y738860D02*
X28163Y740249D01*
X28386Y740920D01*
X28163Y741366D01*
X27694Y741835D01*
Y744839D01*
X30166Y747311D01*
X39185D01*
X48638Y737858D01*
Y663254D01*
X49138Y662754D01*
X50808D01*
X52245Y661317D01*
Y656891D01*
X50808Y655454D01*
X49138D01*
X48638Y654954D01*
Y651854D01*
X49138Y651354D01*
X50808D01*
X52245Y649917D01*
Y645491D01*
X50808Y644054D01*
X49138D01*
X48638Y643554D01*
Y640454D01*
X49138Y639954D01*
X50808D01*
X52245Y638517D01*
Y634091D01*
X50808Y632654D01*
X49138D01*
X48638Y632154D01*
Y629054D01*
X49138Y628554D01*
X50808D01*
X52245Y627117D01*
Y622691D01*
X50808Y621254D01*
X49138D01*
X48638Y620754D01*
Y586093D01*
X58456Y576275D01*
Y561933D01*
X61587Y558802D01*
Y552873D01*
X61419Y552536D01*
X61196Y552091D01*
X61419Y551420D01*
X65254Y549500D01*
G01X33263Y742797D02*
X30491Y741409D01*
X29820Y741634D01*
X29595Y742082D01*
X29594D01*
X29478Y742314D01*
X29294Y742498D01*
Y744176D01*
X30829Y745711D01*
X38522D01*
X40026Y744207D01*
Y742950D01*
X41088Y741888D01*
X41716D01*
X42344Y741889D01*
X43406Y740827D01*
Y739570D01*
X44468Y738508D01*
X45096D01*
X45724Y738509D01*
X47038Y737195D01*
Y662591D01*
X48475Y661154D01*
X50145D01*
X50645Y660654D01*
Y657554D01*
X50145Y657054D01*
X48475D01*
X47038Y655617D01*
Y651191D01*
X48475Y649754D01*
X50145D01*
X50645Y649254D01*
Y646154D01*
X50145Y645654D01*
X48475D01*
X47038Y644217D01*
Y639791D01*
X48475Y638354D01*
X50145D01*
X50645Y637854D01*
Y634754D01*
X50145Y634254D01*
X48475D01*
X47038Y632817D01*
Y628391D01*
X48475Y626954D01*
X50145D01*
X50645Y626454D01*
Y623354D01*
X50145Y622854D01*
X48475D01*
X47038Y621417D01*
Y615509D01*
X46227Y614699D01*
Y613199D01*
X47038Y612389D01*
Y610889D01*
X46227Y610079D01*
Y608579D01*
X47038Y607769D01*
Y606269D01*
X46227Y605459D01*
Y603959D01*
X47038Y603149D01*
Y601649D01*
X46227Y600839D01*
Y599339D01*
X47038Y598529D01*
Y597029D01*
X46227Y596219D01*
Y594719D01*
X47038Y593909D01*
Y592409D01*
X46227Y591599D01*
Y590099D01*
X47038Y589289D01*
Y585430D01*
X56856Y575612D01*
Y561270D01*
X59987Y558139D01*
Y553252D01*
X59762Y552803D01*
X59092Y552578D01*
X55254Y554500D01*
G01X65254Y1577504D02*
X61419Y1579424D01*
X60748Y1579199D01*
X60523Y1578750D01*
X60406Y1578517D01*
X58665Y1576776D01*
Y1552331D01*
X39496Y1533162D01*
Y1459014D01*
X43387Y1455123D01*
Y1372498D01*
X35248Y1364359D01*
X30195D01*
X29025Y1365529D01*
X28800Y1365977D01*
X28129Y1366202D01*
X25393Y1364842D01*
G01X33267Y1368779D02*
X30457Y1367362D01*
X30234Y1366691D01*
X30233Y1366689D01*
X30339Y1366478D01*
X30858Y1365959D01*
X34585D01*
X41787Y1373161D01*
Y1417425D01*
X40816Y1418395D01*
Y1419895D01*
X41787Y1420865D01*
Y1422365D01*
X40816Y1423335D01*
Y1424835D01*
X41787Y1425805D01*
Y1427305D01*
X40816Y1428275D01*
Y1429775D01*
X41787Y1430745D01*
Y1432245D01*
X40816Y1433215D01*
Y1434715D01*
X41787Y1435685D01*
Y1437185D01*
X40816Y1438155D01*
Y1439655D01*
X41787Y1440625D01*
Y1442125D01*
X40816Y1443095D01*
Y1444595D01*
X41787Y1445565D01*
Y1454460D01*
X37896Y1458351D01*
Y1533825D01*
X57065Y1552994D01*
Y1577439D01*
X59092Y1579466D01*
Y1579468D01*
X59093Y1579471D01*
X59314Y1579911D01*
X59091Y1580582D01*
X55254Y1582504D01*
G01X25393Y1380590D02*
X27221Y1378762D01*
X27949D01*
X28672Y1379485D01*
Y1392736D01*
X25095Y1396313D01*
Y1554411D01*
X40324Y1569640D01*
Y1599086D01*
X49026Y1607788D01*
X57613D01*
X61590Y1603811D01*
Y1600760D01*
X59814Y1598984D01*
Y1597082D01*
X60406Y1596491D01*
X60748Y1595809D01*
X61419Y1595584D01*
X65254Y1597504D01*
G01X33267Y1376653D02*
X31835D01*
X30272Y1378216D01*
Y1393399D01*
X26695Y1396976D01*
Y1553748D01*
X41924Y1568977D01*
Y1588291D01*
X42769Y1589135D01*
Y1590635D01*
X41924Y1591479D01*
Y1592979D01*
X42769Y1593823D01*
Y1595323D01*
X41924Y1596167D01*
Y1598423D01*
X42848Y1599347D01*
X43984D01*
X45044Y1600407D01*
Y1601543D01*
X46104Y1602603D01*
X47240D01*
X48300Y1603663D01*
Y1604799D01*
X49689Y1606188D01*
X56950D01*
X59990Y1603148D01*
Y1601423D01*
X58214Y1599647D01*
Y1596419D01*
X59091Y1595542D01*
X59314Y1595097D01*
X59091Y1594426D01*
X55254Y1592504D01*
G54D15*
X30254Y514500D03*
Y559500D03*
Y1572504D03*
Y1617504D03*
G54D24*
X54979Y70500D03*
Y206500D03*
Y279500D03*
Y415500D03*
X203542Y73105D03*
X204069Y152050D03*
X204137Y247568D03*
X204597Y331786D03*
X203541Y421732D03*
X204333Y506517D03*
X206668Y598130D03*
X204596Y681645D03*
X205626Y774526D03*
X205386Y856244D03*
X210091Y947202D03*
X209296Y1032544D03*
X205030Y1122856D03*
X205122Y1206233D03*
X205626Y1299104D03*
X204332Y1380966D03*
X203243Y1474162D03*
X204859Y1557277D03*
X205923Y1648177D03*
X205387Y1731351D03*
X205310Y1823227D03*
X204069Y1900420D03*
X205905Y1998730D03*
X205310Y2043388D03*
G54D33*
X173385Y21890D03*
X183385Y32520D03*
Y21890D03*
X193385Y32520D03*
Y21890D03*
X173385Y196890D03*
X183385D03*
X193385D03*
X183385Y207520D03*
X193385D03*
X173385Y371890D03*
X183385D03*
X193385D03*
X183385Y382520D03*
X193385D03*
X173386Y546890D03*
X183386Y557520D03*
Y546890D03*
X193386Y557520D03*
Y546890D03*
X173386Y721890D03*
X183386Y732520D03*
Y721890D03*
X193386Y732520D03*
Y721890D03*
X173385Y896890D03*
X183385D03*
X193385D03*
X183385Y907520D03*
X193385D03*
X173385Y1071890D03*
X183385D03*
X193385D03*
X183385Y1082520D03*
X193385D03*
X173385Y1246890D03*
X183385Y1257520D03*
Y1246890D03*
X193385Y1257520D03*
Y1246890D03*
X173385Y1421890D03*
X183385Y1432520D03*
Y1421890D03*
X193385Y1432520D03*
Y1421890D03*
X173385Y1596890D03*
X183385D03*
X193385D03*
X183385Y1607520D03*
X193385D03*
X173385Y1771890D03*
X183385D03*
X193385D03*
X183385Y1782520D03*
X193385D03*
X173385Y1946890D03*
X183385Y1957520D03*
Y1946890D03*
X193385Y1957520D03*
Y1946890D03*
X203385Y32520D03*
Y21890D03*
X213385Y32520D03*
Y21890D03*
X203385Y196890D03*
X213385D03*
X203385Y207520D03*
X213385D03*
X203385Y371890D03*
X213385D03*
X203385Y382520D03*
X213385D03*
X203386Y557520D03*
Y546890D03*
X213386Y557520D03*
Y546890D03*
X203386Y732520D03*
Y721890D03*
X213386Y732520D03*
Y721890D03*
X203385Y896890D03*
X213385D03*
X203385Y907520D03*
X213385D03*
X203385Y1071890D03*
X213385D03*
X203385Y1082520D03*
X213385D03*
X203385Y1257520D03*
Y1246890D03*
X213385Y1257520D03*
Y1246890D03*
X203385Y1432520D03*
Y1421890D03*
X213385Y1432520D03*
Y1421890D03*
X203385Y1596890D03*
X213385D03*
X203385Y1607520D03*
X213385D03*
X203385Y1771890D03*
X213385D03*
X203385Y1782520D03*
X213385D03*
X203385Y1957520D03*
Y1946890D03*
X213385Y1957520D03*
Y1946890D03*
X223385Y32520D03*
Y21890D03*
X233385Y32520D03*
Y21890D03*
X243385Y32520D03*
Y21890D03*
X223385Y196890D03*
X233385D03*
X243385D03*
X223385Y207520D03*
X233385D03*
X243385D03*
X223385Y371890D03*
X233385D03*
X243385D03*
X223385Y382520D03*
X233385D03*
X243385D03*
X223386Y557520D03*
Y546890D03*
X233386Y557520D03*
Y546890D03*
X243386Y557520D03*
Y546890D03*
X223386Y732520D03*
Y721890D03*
X233386Y732520D03*
Y721890D03*
X243386Y732520D03*
Y721890D03*
X223385Y896890D03*
X233385D03*
X243385D03*
X223385Y907520D03*
X233385D03*
X243385D03*
X223385Y1071890D03*
X233385D03*
X243385D03*
X223385Y1082520D03*
X233385D03*
X243385D03*
X223385Y1257520D03*
Y1246890D03*
X233385Y1257520D03*
Y1246890D03*
X243385Y1257520D03*
Y1246890D03*
X223385Y1432520D03*
Y1421890D03*
X233385Y1432520D03*
Y1421890D03*
X243385Y1432520D03*
Y1421890D03*
X223385Y1596890D03*
X233385D03*
X243385D03*
X223385Y1607520D03*
X233385D03*
X243385D03*
X223385Y1771890D03*
X233385D03*
X243385D03*
X223385Y1782520D03*
X233385D03*
X243385D03*
X223385Y1957520D03*
Y1946890D03*
X233385Y1957520D03*
Y1946890D03*
X243385Y1957520D03*
Y1946890D03*
X253385Y21890D03*
Y32520D03*
X263385Y21890D03*
Y32520D03*
X253385Y196890D03*
X263385D03*
X253385Y207520D03*
X263385D03*
X253385Y371890D03*
X263385D03*
X253385Y382520D03*
X263385D03*
X253386Y546890D03*
Y557520D03*
X263386Y546890D03*
Y557520D03*
X253386Y721890D03*
Y732520D03*
X263386Y721890D03*
Y732520D03*
X253385Y896890D03*
X263385D03*
X253385Y907520D03*
X263385D03*
X253385Y1071890D03*
X263385D03*
X253385Y1082520D03*
X263385D03*
X253385Y1246890D03*
Y1257520D03*
X263385Y1246890D03*
Y1257520D03*
X253385Y1421890D03*
Y1432520D03*
X263385Y1421890D03*
Y1432520D03*
X253385Y1596890D03*
X263385D03*
X253385Y1607520D03*
X263385D03*
X253385Y1771890D03*
X263385D03*
X253385Y1782520D03*
X263385D03*
X253385Y1946890D03*
Y1957520D03*
X263385Y1946890D03*
Y1957520D03*
X273385Y21890D03*
Y32520D03*
X283385Y21890D03*
Y32520D03*
X273385Y196890D03*
X283385D03*
X273385Y207520D03*
X283385D03*
X273385Y371890D03*
X283385D03*
X273385Y382520D03*
X283385D03*
X273386Y546890D03*
Y557520D03*
X283386Y546890D03*
Y557520D03*
X273386Y721890D03*
Y732520D03*
X283386Y721890D03*
Y732520D03*
X273385Y896890D03*
X283385D03*
X273385Y907520D03*
X283385D03*
X273385Y1071890D03*
X283385D03*
X273385Y1082520D03*
X283385D03*
X273385Y1246890D03*
Y1257520D03*
X283385Y1246890D03*
Y1257520D03*
X273385Y1421890D03*
Y1432520D03*
X283385Y1421890D03*
Y1432520D03*
X273385Y1596890D03*
X283385D03*
X273385Y1607520D03*
X283385D03*
X273385Y1771890D03*
X283385D03*
X273385Y1782520D03*
X283385D03*
X273385Y1946890D03*
Y1957520D03*
X283385Y1946890D03*
Y1957520D03*
X293385Y21890D03*
Y32520D03*
X303385Y21890D03*
Y32520D03*
X313385D03*
Y21890D03*
X293385Y196890D03*
X303385D03*
X313385D03*
X293385Y207520D03*
X303385D03*
X313385D03*
X293385Y371890D03*
X303385D03*
X313385D03*
X293385Y382520D03*
X303385D03*
X313385D03*
X293386Y546890D03*
Y557520D03*
X303386Y546890D03*
Y557520D03*
X313386D03*
Y546890D03*
X293386Y721890D03*
Y732520D03*
X303386Y721890D03*
Y732520D03*
X313386D03*
Y721890D03*
X293385Y896890D03*
X303385D03*
X313385D03*
X293385Y907520D03*
X303385D03*
X313385D03*
X293385Y1071890D03*
X303385D03*
X313385D03*
X293385Y1082520D03*
X303385D03*
X313385D03*
X293385Y1246890D03*
Y1257520D03*
X303385Y1246890D03*
Y1257520D03*
X313385D03*
Y1246890D03*
X293385Y1421890D03*
Y1432520D03*
X303385Y1421890D03*
Y1432520D03*
X313385D03*
Y1421890D03*
X293385Y1596890D03*
X303385D03*
X313385D03*
X293385Y1607520D03*
X303385D03*
X313385D03*
X293385Y1771890D03*
X303385D03*
X313385D03*
X293385Y1782520D03*
X303385D03*
X313385D03*
X293385Y1946890D03*
Y1957520D03*
X303385Y1946890D03*
Y1957520D03*
X313385D03*
Y1946890D03*
X337165Y24705D03*
X323385Y32520D03*
Y21890D03*
X337165Y34705D03*
Y199705D03*
X323385Y196890D03*
X337165Y209705D03*
X323385Y207520D03*
Y371890D03*
X337165Y374705D03*
Y384705D03*
X323385Y382520D03*
X337166Y549705D03*
Y559705D03*
X323386Y557520D03*
Y546890D03*
X337166Y724705D03*
X323386Y732520D03*
Y721890D03*
X337166Y734705D03*
X337165Y899705D03*
X323385Y896890D03*
X337165Y909705D03*
X323385Y907520D03*
Y1071890D03*
X337165Y1074705D03*
Y1084705D03*
X323385Y1082520D03*
X337165Y1249705D03*
Y1259705D03*
X323385Y1257520D03*
Y1246890D03*
X337165Y1424705D03*
Y1434705D03*
X323385Y1432520D03*
Y1421890D03*
X337165Y1599705D03*
X323385Y1596890D03*
X337165Y1609705D03*
X323385Y1607520D03*
Y1771890D03*
X337165Y1774705D03*
Y1784705D03*
X323385Y1782520D03*
X337165Y1949705D03*
Y1959705D03*
X323385Y1957520D03*
Y1946890D03*
X342165Y19705D03*
Y29705D03*
X347165Y24705D03*
X352165Y19705D03*
Y29705D03*
X357165Y24705D03*
X362165Y19705D03*
Y29705D03*
X347165Y34705D03*
X357165D03*
X342165Y194705D03*
X347165Y199705D03*
X352165Y194705D03*
X357165Y199705D03*
X362165Y194705D03*
X342165Y204705D03*
X347165Y209705D03*
X352165Y204705D03*
X357165Y209705D03*
X362165Y204705D03*
X342165Y369705D03*
X352165D03*
X362165D03*
X342165Y379705D03*
X347165Y374705D03*
Y384705D03*
X352165Y379705D03*
X357165Y374705D03*
Y384705D03*
X362165Y379705D03*
X342166Y544705D03*
Y554705D03*
X347166Y549705D03*
Y559705D03*
X352166Y544705D03*
Y554705D03*
X357166Y549705D03*
Y559705D03*
X362166Y544705D03*
Y554705D03*
X342166Y719705D03*
Y729705D03*
X347166Y724705D03*
X352166Y719705D03*
Y729705D03*
X357166Y724705D03*
X362166Y719705D03*
Y729705D03*
X347166Y734705D03*
X357166D03*
X342165Y894705D03*
X347165Y899705D03*
X352165Y894705D03*
X357165Y899705D03*
X362165Y894705D03*
X342165Y904705D03*
X347165Y909705D03*
X352165Y904705D03*
X357165Y909705D03*
X362165Y904705D03*
X342165Y1069705D03*
X352165D03*
X362165D03*
X342165Y1079705D03*
X347165Y1074705D03*
Y1084705D03*
X352165Y1079705D03*
X357165Y1074705D03*
Y1084705D03*
X362165Y1079705D03*
X342165Y1244705D03*
Y1254705D03*
X347165Y1249705D03*
Y1259705D03*
X352165Y1244705D03*
Y1254705D03*
X357165Y1249705D03*
Y1259705D03*
X362165Y1244705D03*
Y1254705D03*
X342165Y1419705D03*
Y1429705D03*
X347165Y1424705D03*
Y1434705D03*
X352165Y1419705D03*
Y1429705D03*
X357165Y1424705D03*
Y1434705D03*
X362165Y1419705D03*
Y1429705D03*
X342165Y1594705D03*
X347165Y1599705D03*
X352165Y1594705D03*
X357165Y1599705D03*
X362165Y1594705D03*
X342165Y1604705D03*
X347165Y1609705D03*
X352165Y1604705D03*
X357165Y1609705D03*
X362165Y1604705D03*
X342165Y1769705D03*
X352165D03*
X362165D03*
X342165Y1779705D03*
X347165Y1774705D03*
Y1784705D03*
X352165Y1779705D03*
X357165Y1774705D03*
Y1784705D03*
X362165Y1779705D03*
X342165Y1944705D03*
Y1954705D03*
X347165Y1949705D03*
Y1959705D03*
X352165Y1944705D03*
Y1954705D03*
X357165Y1949705D03*
Y1959705D03*
X362165Y1944705D03*
Y1954705D03*
G54D43*
G01X-723776Y2987387D02*
Y-376795D01*
Y-489221D01*
X1782976D01*
Y-376795D01*
Y2987387D01*
X-723776D01*
G01X-4000Y-62500D02*
Y-137500D01*
X496000D01*
Y-62500D01*
X-4000D01*
G01X8000Y-127500D02*
Y-132500D01*
G01X6543Y-127500D02*
X9457D01*
G01X14367Y-132500D02*
X11833D01*
Y-127500D01*
X14367D01*
G01X13353Y-129917D02*
X11833D01*
G01X16933Y-127500D02*
Y-132500D01*
X19467D01*
G01X23300Y-132667D02*
X23173Y-132583D01*
Y-132417D01*
X23300Y-132333D01*
X23427Y-132417D01*
Y-132583D01*
X23300Y-132667D01*
G01Y-130417D02*
X23173Y-130333D01*
Y-130167D01*
X23300Y-130083D01*
X23427Y-130167D01*
Y-130333D01*
X23300Y-130417D01*
G01X28083Y-134167D02*
X27450Y-133333D01*
X27133Y-132500D01*
Y-129167D01*
X27450Y-128333D01*
X28083Y-127500D01*
G01X33500D02*
X32993Y-127667D01*
X32613Y-128083D01*
X32360Y-128583D01*
X32170Y-129250D01*
X32107Y-130000D01*
X32170Y-130750D01*
X32360Y-131417D01*
X32613Y-131917D01*
X32993Y-132333D01*
X33500Y-132500D01*
X34007Y-132333D01*
X34387Y-131917D01*
X34640Y-131417D01*
X34830Y-130750D01*
X34893Y-130000D01*
X34830Y-129250D01*
X34640Y-128583D01*
X34387Y-128083D01*
X34007Y-127667D01*
X33500Y-127500D01*
G01X37207Y-131500D02*
X37587Y-132083D01*
X38093Y-132417D01*
X38663Y-132500D01*
X39170Y-132417D01*
X39677Y-132000D01*
X39993Y-131500D01*
X40057Y-131000D01*
X39930Y-130417D01*
X39487Y-130000D01*
X39043Y-129833D01*
X38473D01*
G01X39043D02*
X39423Y-129583D01*
X39740Y-129167D01*
X39867Y-128667D01*
X39740Y-128167D01*
X39423Y-127750D01*
X38853Y-127500D01*
X38283Y-127583D01*
X37713Y-127917D01*
G01X44017Y-134167D02*
X44650Y-133333D01*
X44967Y-132500D01*
Y-129167D01*
X44650Y-128333D01*
X44017Y-127500D01*
G01X47407Y-131500D02*
X47787Y-132083D01*
X48293Y-132417D01*
X48863Y-132500D01*
X49370Y-132417D01*
X49877Y-132000D01*
X50193Y-131500D01*
X50257Y-131000D01*
X50130Y-130417D01*
X49687Y-130000D01*
X49243Y-129833D01*
X48673D01*
G01X49243D02*
X49623Y-129583D01*
X49940Y-129167D01*
X50067Y-128667D01*
X49940Y-128167D01*
X49623Y-127750D01*
X49053Y-127500D01*
X48483Y-127583D01*
X47913Y-127917D01*
G01X52697Y-128333D02*
X53077Y-127833D01*
X53520Y-127583D01*
X54027Y-127500D01*
X54660Y-127667D01*
X55103Y-128083D01*
X55230Y-128583D01*
X55167Y-129083D01*
X54913Y-129500D01*
X53647Y-130333D01*
X53077Y-130917D01*
X52697Y-131750D01*
X52570Y-132500D01*
X55230D01*
G01X58873D02*
X59000Y-131417D01*
X59190Y-130500D01*
X59443Y-129667D01*
X59760Y-128750D01*
X60267Y-127500D01*
X57733D01*
G01X63277Y-130833D02*
X64923D01*
G01X67997Y-128333D02*
X68377Y-127833D01*
X68820Y-127583D01*
X69327Y-127500D01*
X69960Y-127667D01*
X70403Y-128083D01*
X70530Y-128583D01*
X70467Y-129083D01*
X70213Y-129500D01*
X68947Y-130333D01*
X68377Y-130917D01*
X67997Y-131750D01*
X67870Y-132500D01*
X70530D01*
G01X72907Y-131500D02*
X73287Y-132083D01*
X73793Y-132417D01*
X74363Y-132500D01*
X74870Y-132417D01*
X75377Y-132000D01*
X75693Y-131500D01*
X75757Y-131000D01*
X75630Y-130417D01*
X75187Y-130000D01*
X74743Y-129833D01*
X74173D01*
G01X74743D02*
X75123Y-129583D01*
X75440Y-129167D01*
X75567Y-128667D01*
X75440Y-128167D01*
X75123Y-127750D01*
X74553Y-127500D01*
X73983Y-127583D01*
X73413Y-127917D01*
G01X80160Y-132500D02*
Y-127500D01*
X77817Y-131083D01*
X80983D01*
G01X83107Y-131750D02*
X83487Y-132167D01*
X83930Y-132417D01*
X84500Y-132500D01*
X85070Y-132333D01*
X85513Y-132000D01*
X85830Y-131417D01*
X85893Y-130750D01*
X85767Y-130083D01*
X85450Y-129667D01*
X85007Y-129333D01*
X84563Y-129250D01*
X84120Y-129333D01*
X83550Y-129667D01*
X83740Y-127500D01*
X85450D01*
G01X93497Y-132500D02*
Y-127500D01*
X95903D01*
G01X95017Y-129917D02*
X93497D01*
G01X98217Y-132500D02*
X99800Y-127500D01*
X101383Y-132500D01*
G01X100813Y-130750D02*
X98787D01*
G01X103570Y-132500D02*
X106230Y-127500D01*
G01X103570D02*
X106230Y-132500D01*
G01X110000Y-132667D02*
X109873Y-132583D01*
Y-132417D01*
X110000Y-132333D01*
X110127Y-132417D01*
Y-132583D01*
X110000Y-132667D01*
G01Y-130417D02*
X109873Y-130333D01*
Y-130167D01*
X110000Y-130083D01*
X110127Y-130167D01*
Y-130333D01*
X110000Y-130417D01*
G01X114783Y-134167D02*
X114150Y-133333D01*
X113833Y-132500D01*
Y-129167D01*
X114150Y-128333D01*
X114783Y-127500D01*
G01X120200D02*
X119693Y-127667D01*
X119313Y-128083D01*
X119060Y-128583D01*
X118870Y-129250D01*
X118807Y-130000D01*
X118870Y-130750D01*
X119060Y-131417D01*
X119313Y-131917D01*
X119693Y-132333D01*
X120200Y-132500D01*
X120707Y-132333D01*
X121087Y-131917D01*
X121340Y-131417D01*
X121530Y-130750D01*
X121593Y-130000D01*
X121530Y-129250D01*
X121340Y-128583D01*
X121087Y-128083D01*
X120707Y-127667D01*
X120200Y-127500D01*
G01X123907Y-131500D02*
X124287Y-132083D01*
X124793Y-132417D01*
X125363Y-132500D01*
X125870Y-132417D01*
X126377Y-132000D01*
X126693Y-131500D01*
X126757Y-131000D01*
X126630Y-130417D01*
X126187Y-130000D01*
X125743Y-129833D01*
X125173D01*
G01X125743D02*
X126123Y-129583D01*
X126440Y-129167D01*
X126567Y-128667D01*
X126440Y-128167D01*
X126123Y-127750D01*
X125553Y-127500D01*
X124983Y-127583D01*
X124413Y-127917D01*
G01X130717Y-134167D02*
X131350Y-133333D01*
X131667Y-132500D01*
Y-129167D01*
X131350Y-128333D01*
X130717Y-127500D01*
G01X134107Y-131500D02*
X134487Y-132083D01*
X134993Y-132417D01*
X135563Y-132500D01*
X136070Y-132417D01*
X136577Y-132000D01*
X136893Y-131500D01*
X136957Y-131000D01*
X136830Y-130417D01*
X136387Y-130000D01*
X135943Y-129833D01*
X135373D01*
G01X135943D02*
X136323Y-129583D01*
X136640Y-129167D01*
X136767Y-128667D01*
X136640Y-128167D01*
X136323Y-127750D01*
X135753Y-127500D01*
X135183Y-127583D01*
X134613Y-127917D01*
G01X139523Y-131917D02*
X139967Y-132333D01*
X140473Y-132500D01*
X140980Y-132333D01*
X141423Y-131833D01*
X141740Y-131083D01*
X141867Y-130333D01*
Y-129417D01*
X141740Y-128667D01*
X141423Y-128000D01*
X141043Y-127667D01*
X140600Y-127500D01*
X140093Y-127667D01*
X139713Y-128000D01*
X139460Y-128500D01*
X139333Y-129167D01*
X139460Y-129750D01*
X139777Y-130333D01*
X140157Y-130667D01*
X140600Y-130750D01*
X141107Y-130583D01*
X141487Y-130167D01*
X141867Y-129417D01*
G01X145573Y-132500D02*
X145700Y-131417D01*
X145890Y-130500D01*
X146143Y-129667D01*
X146460Y-128750D01*
X146967Y-127500D01*
X144433D01*
G01X149977Y-130833D02*
X151623D01*
G01X154507Y-131500D02*
X154887Y-132083D01*
X155393Y-132417D01*
X155963Y-132500D01*
X156470Y-132417D01*
X156977Y-132000D01*
X157293Y-131500D01*
X157357Y-131000D01*
X157230Y-130417D01*
X156787Y-130000D01*
X156343Y-129833D01*
X155773D01*
G01X156343D02*
X156723Y-129583D01*
X157040Y-129167D01*
X157167Y-128667D01*
X157040Y-128167D01*
X156723Y-127750D01*
X156153Y-127500D01*
X155583Y-127583D01*
X155013Y-127917D01*
G01X159797Y-130417D02*
X160240Y-129833D01*
X160620Y-129500D01*
X161127Y-129333D01*
X161570Y-129500D01*
X161887Y-129833D01*
X162140Y-130333D01*
X162203Y-130917D01*
X162140Y-131417D01*
X161887Y-131917D01*
X161507Y-132333D01*
X161063Y-132500D01*
X160557Y-132333D01*
X160113Y-131833D01*
X159860Y-131083D01*
X159797Y-130250D01*
X159923Y-129167D01*
X160113Y-128583D01*
X160430Y-128000D01*
X160873Y-127583D01*
X161317Y-127500D01*
X161760Y-127667D01*
X162077Y-128083D01*
G01X166100Y-132500D02*
Y-127500D01*
X165340Y-128500D01*
G01Y-132500D02*
X166860D01*
G01X171960D02*
Y-127500D01*
X169617Y-131083D01*
X172783D01*
G01X191000Y-62500D02*
Y-137500D01*
G01Y-112500D02*
X294000D01*
Y-87500D01*
G01X191000D02*
X294000D01*
G01X301507Y-122500D02*
Y-117500D01*
X302773D01*
X303280Y-117750D01*
X303660Y-118083D01*
X303977Y-118583D01*
X304230Y-119167D01*
X304293Y-120000D01*
X304230Y-120833D01*
X303977Y-121417D01*
X303660Y-121917D01*
X303280Y-122250D01*
X302773Y-122500D01*
X301507D01*
G01X306417D02*
X308000Y-117500D01*
X309583Y-122500D01*
G01X309013Y-120750D02*
X306987D01*
G01X313100Y-117500D02*
Y-122500D01*
G01X311643Y-117500D02*
X314557D01*
G01X319467Y-122500D02*
X316933D01*
Y-117500D01*
X319467D01*
G01X318453Y-119917D02*
X316933D01*
G01X323300Y-122667D02*
X323173Y-122583D01*
Y-122417D01*
X323300Y-122333D01*
X323427Y-122417D01*
Y-122583D01*
X323300Y-122667D01*
G01Y-120417D02*
X323173Y-120333D01*
Y-120167D01*
X323300Y-120083D01*
X323427Y-120167D01*
Y-120333D01*
X323300Y-120417D01*
G01X296000Y-62500D02*
Y-137500D01*
G01X294000Y-62500D02*
Y-137500D01*
G01X301633Y-97500D02*
Y-92500D01*
X303153D01*
X303660Y-92750D01*
X304040Y-93333D01*
X304167Y-94000D01*
X304040Y-94667D01*
X303723Y-95167D01*
X303153Y-95417D01*
X301633D01*
G01X306860Y-97667D02*
X309140Y-92500D01*
G01X311643Y-97500D02*
Y-92500D01*
X314557Y-97500D01*
Y-92500D01*
G01X318200Y-97667D02*
X318073Y-97583D01*
Y-97417D01*
X318200Y-97333D01*
X318327Y-97417D01*
Y-97583D01*
X318200Y-97667D01*
G01Y-95417D02*
X318073Y-95333D01*
Y-95167D01*
X318200Y-95083D01*
X318327Y-95167D01*
Y-95333D01*
X318200Y-95417D01*
G01X296000Y-112500D02*
X496000D01*
G01X301633Y-72500D02*
Y-67500D01*
X303153D01*
X303660Y-67750D01*
X304040Y-68333D01*
X304167Y-69000D01*
X304040Y-69667D01*
X303723Y-70167D01*
X303153Y-70417D01*
X301633D01*
G01X306733Y-72500D02*
Y-67500D01*
X308317D01*
X308823Y-67750D01*
X309140Y-68083D01*
X309267Y-68750D01*
X309140Y-69417D01*
X308760Y-69833D01*
X308317Y-70083D01*
X306733D01*
G01X308317D02*
X309267Y-72500D01*
G01X313100D02*
X312593Y-72417D01*
X312150Y-72083D01*
X311770Y-71583D01*
X311517Y-71000D01*
X311390Y-70333D01*
Y-69667D01*
X311517Y-69000D01*
X311770Y-68417D01*
X312150Y-67917D01*
X312593Y-67583D01*
X313100Y-67500D01*
X313607Y-67583D01*
X314050Y-67917D01*
X314430Y-68417D01*
X314683Y-69000D01*
X314810Y-69667D01*
Y-70333D01*
X314683Y-71000D01*
X314430Y-71583D01*
X314050Y-72083D01*
X313607Y-72417D01*
X313100Y-72500D01*
G01X316933Y-71500D02*
X317250Y-72000D01*
X317630Y-72333D01*
X318073Y-72500D01*
X318580Y-72333D01*
X318960Y-72000D01*
X319340Y-71500D01*
X319467Y-70833D01*
Y-67500D01*
G01X324567Y-72500D02*
X322033D01*
Y-67500D01*
X324567D01*
G01X323553Y-69917D02*
X322033D01*
G01X329793Y-67917D02*
X329413Y-67667D01*
X328970Y-67500D01*
X328463D01*
X327893Y-67750D01*
X327450Y-68167D01*
X327133Y-68667D01*
X326880Y-69500D01*
X326817Y-70250D01*
X326943Y-71000D01*
X327133Y-71500D01*
X327513Y-72000D01*
X327957Y-72333D01*
X328400Y-72500D01*
X328843D01*
X329287Y-72333D01*
X329667Y-72083D01*
X329983Y-71750D01*
G01X333500Y-67500D02*
Y-72500D01*
G01X332043Y-67500D02*
X334957D01*
G01X338600Y-72667D02*
X338473Y-72583D01*
Y-72417D01*
X338600Y-72333D01*
X338727Y-72417D01*
Y-72583D01*
X338600Y-72667D01*
G01Y-70417D02*
X338473Y-70333D01*
Y-70167D01*
X338600Y-70083D01*
X338727Y-70167D01*
Y-70333D01*
X338600Y-70417D01*
G01X296000Y-87500D02*
X496000D01*
G01X411000Y-112500D02*
Y-137500D01*
G01X416633Y-122500D02*
Y-117500D01*
X418217D01*
X418723Y-117750D01*
X419040Y-118083D01*
X419167Y-118750D01*
X419040Y-119417D01*
X418660Y-119833D01*
X418217Y-120083D01*
X416633D01*
G01X418217D02*
X419167Y-122500D01*
G01X424267D02*
X421733D01*
Y-117500D01*
X424267D01*
G01X423253Y-119917D02*
X421733D01*
G01X426517Y-117500D02*
X428100Y-122500D01*
X429683Y-117500D01*
G01X433200Y-122667D02*
X433073Y-122583D01*
Y-122417D01*
X433200Y-122333D01*
X433327Y-122417D01*
Y-122583D01*
X433200Y-122667D01*
G01Y-120417D02*
X433073Y-120333D01*
Y-120167D01*
X433200Y-120083D01*
X433327Y-120167D01*
Y-120333D01*
X433200Y-120417D01*
G01X460000Y-112500D02*
Y-137500D01*
G01X-723776Y2987387D02*
Y-376795D01*
Y-489221D01*
X1782976D01*
Y-376795D01*
Y2987387D01*
X-723776D01*
G01X6705Y-124160D02*
X7332Y-124685D01*
X8037Y-125000D01*
X8663D01*
X9290Y-124685D01*
X9760Y-124160D01*
X9995Y-123425D01*
X9838Y-122690D01*
X9447Y-122060D01*
X8742Y-121640D01*
X7802Y-121430D01*
X7253Y-121010D01*
X7018Y-120275D01*
X7175Y-119540D01*
X7567Y-119015D01*
X8115Y-118700D01*
X8663D01*
X9212Y-118910D01*
X9682Y-119435D01*
G01X13005Y-125000D02*
Y-118700D01*
G01X16295D02*
Y-125000D01*
G01Y-121850D02*
X13005D01*
G01X20010Y-118700D02*
X21890D01*
G01X20950D02*
Y-125000D01*
G01X20010D02*
X21890D01*
G01X28817D02*
X25683D01*
Y-118700D01*
X28817D01*
G01X27563Y-121745D02*
X25683D01*
G01X31748Y-125000D02*
Y-118700D01*
X35352Y-125000D01*
Y-118700D01*
G01X39693Y-126155D02*
X40007Y-124790D01*
G01X46150Y-118700D02*
Y-125000D01*
G01X44348Y-118700D02*
X47952D01*
G01X50492Y-125000D02*
X52450Y-118700D01*
X54408Y-125000D01*
G01X53703Y-122795D02*
X51197D01*
G01X57810Y-118700D02*
X59690D01*
G01X58750D02*
Y-125000D01*
G01X57810D02*
X59690D01*
G01X62700Y-118700D02*
X63797Y-125000D01*
X65050Y-118700D01*
X66303Y-125000D01*
X67400Y-118700D01*
G01X69392Y-125000D02*
X71350Y-118700D01*
X73308Y-125000D01*
G01X72603Y-122795D02*
X70097D01*
G01X75848Y-125000D02*
Y-118700D01*
X79452Y-125000D01*
Y-118700D01*
G01X88683Y-125000D02*
Y-118700D01*
X90642D01*
X91268Y-119015D01*
X91660Y-119435D01*
X91817Y-120275D01*
X91660Y-121115D01*
X91190Y-121640D01*
X90642Y-121955D01*
X88683D01*
G01X90642D02*
X91817Y-125000D01*
G01X96550Y-125210D02*
X96393Y-125105D01*
Y-124895D01*
X96550Y-124790D01*
X96707Y-124895D01*
Y-125105D01*
X96550Y-125210D01*
G01X102850Y-125000D02*
X102223Y-124895D01*
X101675Y-124475D01*
X101205Y-123845D01*
X100892Y-123110D01*
X100735Y-122270D01*
Y-121430D01*
X100892Y-120590D01*
X101205Y-119855D01*
X101675Y-119225D01*
X102223Y-118805D01*
X102850Y-118700D01*
X103477Y-118805D01*
X104025Y-119225D01*
X104495Y-119855D01*
X104808Y-120590D01*
X104965Y-121430D01*
Y-122270D01*
X104808Y-123110D01*
X104495Y-123845D01*
X104025Y-124475D01*
X103477Y-124895D01*
X102850Y-125000D01*
G01X109150Y-125210D02*
X108993Y-125105D01*
Y-124895D01*
X109150Y-124790D01*
X109307Y-124895D01*
Y-125105D01*
X109150Y-125210D01*
G01X117173Y-119225D02*
X116703Y-118910D01*
X116155Y-118700D01*
X115528D01*
X114823Y-119015D01*
X114275Y-119540D01*
X113883Y-120170D01*
X113570Y-121220D01*
X113492Y-122165D01*
X113648Y-123110D01*
X113883Y-123740D01*
X114353Y-124370D01*
X114902Y-124790D01*
X115450Y-125000D01*
X115998D01*
X116547Y-124790D01*
X117017Y-124475D01*
X117408Y-124055D01*
G01X121750Y-125210D02*
X121593Y-125105D01*
Y-124895D01*
X121750Y-124790D01*
X121907Y-124895D01*
Y-125105D01*
X121750Y-125210D01*
G01X6627Y-115000D02*
Y-108700D01*
G01X9603D02*
X6627Y-112585D01*
G01X10073Y-115000D02*
X7958Y-110800D01*
G01X12927Y-108700D02*
Y-113215D01*
X13240Y-114160D01*
X13867Y-114790D01*
X14650Y-115000D01*
X15433Y-114790D01*
X16060Y-114160D01*
X16373Y-113215D01*
Y-108700D01*
G01X22517Y-115000D02*
X19383D01*
Y-108700D01*
X22517D01*
G01X21263Y-111745D02*
X19383D01*
G01X26310Y-108700D02*
X28190D01*
G01X27250D02*
Y-115000D01*
G01X26310D02*
X28190D01*
G01X38205Y-114160D02*
X38832Y-114685D01*
X39537Y-115000D01*
X40163D01*
X40790Y-114685D01*
X41260Y-114160D01*
X41495Y-113425D01*
X41338Y-112690D01*
X40947Y-112060D01*
X40242Y-111640D01*
X39302Y-111430D01*
X38753Y-111010D01*
X38518Y-110275D01*
X38675Y-109540D01*
X39067Y-109015D01*
X39615Y-108700D01*
X40163D01*
X40712Y-108910D01*
X41182Y-109435D01*
G01X44505Y-115000D02*
Y-108700D01*
G01X47795D02*
Y-115000D01*
G01Y-111850D02*
X44505D01*
G01X50492Y-115000D02*
X52450Y-108700D01*
X54408Y-115000D01*
G01X53703Y-112795D02*
X51197D01*
G01X56948Y-115000D02*
Y-108700D01*
X60552Y-115000D01*
Y-108700D01*
G01X69705Y-115000D02*
Y-108700D01*
G01X72995D02*
Y-115000D01*
G01Y-111850D02*
X69705D01*
G01X76005Y-114160D02*
X76632Y-114685D01*
X77337Y-115000D01*
X77963D01*
X78590Y-114685D01*
X79060Y-114160D01*
X79295Y-113425D01*
X79138Y-112690D01*
X78747Y-112060D01*
X78042Y-111640D01*
X77102Y-111430D01*
X76553Y-111010D01*
X76318Y-110275D01*
X76475Y-109540D01*
X76867Y-109015D01*
X77415Y-108700D01*
X77963D01*
X78512Y-108910D01*
X78982Y-109435D01*
G01X83010Y-108700D02*
X84890D01*
G01X83950D02*
Y-115000D01*
G01X83010D02*
X84890D01*
G01X88292D02*
X90250Y-108700D01*
X92208Y-115000D01*
G01X91503Y-112795D02*
X88997D01*
G01X94748Y-115000D02*
Y-108700D01*
X98352Y-115000D01*
Y-108700D01*
G01X103320Y-111850D02*
X104887D01*
Y-113740D01*
X104417Y-114370D01*
X103868Y-114790D01*
X103085Y-115000D01*
X102302Y-114790D01*
X101753Y-114370D01*
X101283Y-113740D01*
X100970Y-113005D01*
X100813Y-112165D01*
Y-111430D01*
X100970Y-110800D01*
X101283Y-110065D01*
X101753Y-109435D01*
X102223Y-109015D01*
X102850Y-108700D01*
X103398D01*
X104025Y-108910D01*
X104495Y-109330D01*
G01X108993Y-116155D02*
X109307Y-114790D01*
G01X115450Y-108700D02*
Y-115000D01*
G01X113648Y-108700D02*
X117252D01*
G01X119792Y-115000D02*
X121750Y-108700D01*
X123708Y-115000D01*
G01X123003Y-112795D02*
X120497D01*
G01X128050Y-115000D02*
X127423Y-114895D01*
X126875Y-114475D01*
X126405Y-113845D01*
X126092Y-113110D01*
X125935Y-112270D01*
Y-111430D01*
X126092Y-110590D01*
X126405Y-109855D01*
X126875Y-109225D01*
X127423Y-108805D01*
X128050Y-108700D01*
X128677Y-108805D01*
X129225Y-109225D01*
X129695Y-109855D01*
X130008Y-110590D01*
X130165Y-111430D01*
Y-112270D01*
X130008Y-113110D01*
X129695Y-113845D01*
X129225Y-114475D01*
X128677Y-114895D01*
X128050Y-115000D01*
G01X140650D02*
Y-112165D01*
X139083Y-108700D01*
G01X142217D02*
X140650Y-112165D01*
G01X145227Y-108700D02*
Y-113215D01*
X145540Y-114160D01*
X146167Y-114790D01*
X146950Y-115000D01*
X147733Y-114790D01*
X148360Y-114160D01*
X148673Y-113215D01*
Y-108700D01*
G01X151292Y-115000D02*
X153250Y-108700D01*
X155208Y-115000D01*
G01X154503Y-112795D02*
X151997D01*
G01X157748Y-115000D02*
Y-108700D01*
X161352Y-115000D01*
Y-108700D01*
G01X30650Y-92300D02*
X28130Y-91883D01*
X25925Y-90217D01*
X24035Y-87717D01*
X22775Y-84800D01*
X22145Y-81467D01*
Y-78133D01*
X22775Y-74800D01*
X24035Y-71883D01*
X25925Y-69384D01*
X28130Y-67717D01*
X30650Y-67300D01*
X33170Y-67717D01*
X35375Y-69384D01*
X37265Y-71883D01*
X38525Y-74800D01*
X39155Y-78133D01*
Y-81467D01*
X38525Y-84800D01*
X37265Y-87717D01*
X35375Y-90217D01*
X33170Y-91883D01*
X30650Y-92300D01*
G01X33170Y-85633D02*
X36950Y-92300D01*
G01X50495Y-75634D02*
Y-87300D01*
X51755Y-90217D01*
X53645Y-91883D01*
X55850Y-92300D01*
X58055Y-91883D01*
X59945Y-90217D01*
X61205Y-87300D01*
G01Y-92300D02*
Y-75634D01*
G01X86720Y-92300D02*
Y-75634D01*
G01Y-78550D02*
X85460Y-76884D01*
X83570Y-76050D01*
X81365Y-75634D01*
X79160Y-76467D01*
X77270Y-78133D01*
X76010Y-80634D01*
X75380Y-83967D01*
X76010Y-87300D01*
X77270Y-89801D01*
X79160Y-91467D01*
X81365Y-92300D01*
X83570Y-91883D01*
X85460Y-90634D01*
X86720Y-88967D01*
G01X100895Y-92300D02*
Y-75634D01*
G01Y-79800D02*
X102155Y-77717D01*
X104045Y-76050D01*
X106565Y-75634D01*
X108770Y-76050D01*
X110660Y-77717D01*
X111605Y-80634D01*
Y-92300D01*
G01X131450Y-67300D02*
Y-92300D01*
G01X127040Y-75634D02*
X135860D01*
G01X162320Y-92300D02*
Y-75634D01*
G01Y-78550D02*
X161060Y-76884D01*
X159170Y-76050D01*
X156965Y-75634D01*
X154760Y-76467D01*
X152870Y-78133D01*
X151610Y-80634D01*
X150980Y-83967D01*
X151610Y-87300D01*
X152870Y-89801D01*
X154760Y-91467D01*
X156965Y-92300D01*
X159170Y-91883D01*
X161060Y-90634D01*
X162320Y-88967D01*
G01X6548Y-105000D02*
Y-98700D01*
X10152Y-105000D01*
Y-98700D01*
G01X14650Y-105000D02*
X14023Y-104895D01*
X13475Y-104475D01*
X13005Y-103845D01*
X12692Y-103110D01*
X12535Y-102270D01*
Y-101430D01*
X12692Y-100590D01*
X13005Y-99855D01*
X13475Y-99225D01*
X14023Y-98805D01*
X14650Y-98700D01*
X15277Y-98805D01*
X15825Y-99225D01*
X16295Y-99855D01*
X16608Y-100590D01*
X16765Y-101430D01*
Y-102270D01*
X16608Y-103110D01*
X16295Y-103845D01*
X15825Y-104475D01*
X15277Y-104895D01*
X14650Y-105000D01*
G01X20950Y-105210D02*
X20793Y-105105D01*
Y-104895D01*
X20950Y-104790D01*
X21107Y-104895D01*
Y-105105D01*
X20950Y-105210D01*
G01X27250Y-105000D02*
Y-98700D01*
X26310Y-99960D01*
G01Y-105000D02*
X28190D01*
G01X33550D02*
X34098Y-104895D01*
X34725Y-104580D01*
X35117Y-104055D01*
X35273Y-103320D01*
X35117Y-102585D01*
X34647Y-101955D01*
X33942Y-101640D01*
X33158D01*
X32688Y-101430D01*
X32297Y-100905D01*
X32140Y-100170D01*
X32375Y-99435D01*
X32923Y-98910D01*
X33550Y-98700D01*
X34177Y-98910D01*
X34725Y-99435D01*
X34960Y-100170D01*
X34803Y-100905D01*
X34412Y-101430D01*
X33942Y-101640D01*
X33158D01*
X32453Y-101955D01*
X31983Y-102585D01*
X31827Y-103320D01*
X31983Y-104055D01*
X32375Y-104580D01*
X33002Y-104895D01*
X33550Y-105000D01*
G01X39850D02*
X40398Y-104895D01*
X41025Y-104580D01*
X41417Y-104055D01*
X41573Y-103320D01*
X41417Y-102585D01*
X40947Y-101955D01*
X40242Y-101640D01*
X39458D01*
X38988Y-101430D01*
X38597Y-100905D01*
X38440Y-100170D01*
X38675Y-99435D01*
X39223Y-98910D01*
X39850Y-98700D01*
X40477Y-98910D01*
X41025Y-99435D01*
X41260Y-100170D01*
X41103Y-100905D01*
X40712Y-101430D01*
X40242Y-101640D01*
X39458D01*
X38753Y-101955D01*
X38283Y-102585D01*
X38127Y-103320D01*
X38283Y-104055D01*
X38675Y-104580D01*
X39302Y-104895D01*
X39850Y-105000D01*
G01X45993Y-106155D02*
X46307Y-104790D01*
G01X50100Y-98700D02*
X51197Y-105000D01*
X52450Y-98700D01*
X53703Y-105000D01*
X54800Y-98700D01*
G01X60317Y-105000D02*
X57183D01*
Y-98700D01*
X60317D01*
G01X59063Y-101745D02*
X57183D01*
G01X63248Y-105000D02*
Y-98700D01*
X66852Y-105000D01*
Y-98700D01*
G01X76005Y-105000D02*
Y-98700D01*
G01X79295D02*
Y-105000D01*
G01Y-101850D02*
X76005D01*
G01X81600Y-98700D02*
X82697Y-105000D01*
X83950Y-98700D01*
X85203Y-105000D01*
X86300Y-98700D01*
G01X88292Y-105000D02*
X90250Y-98700D01*
X92208Y-105000D01*
G01X91503Y-102795D02*
X88997D01*
G01X101362Y-99750D02*
X101832Y-99120D01*
X102380Y-98805D01*
X103007Y-98700D01*
X103790Y-98910D01*
X104338Y-99435D01*
X104495Y-100065D01*
X104417Y-100695D01*
X104103Y-101220D01*
X102537Y-102270D01*
X101832Y-103005D01*
X101362Y-104055D01*
X101205Y-105000D01*
X104495D01*
G01X107348D02*
Y-98700D01*
X110952Y-105000D01*
Y-98700D01*
G01X113727Y-105000D02*
Y-98700D01*
X115293D01*
X115920Y-99015D01*
X116390Y-99435D01*
X116782Y-100065D01*
X117095Y-100800D01*
X117173Y-101850D01*
X117095Y-102900D01*
X116782Y-103635D01*
X116390Y-104265D01*
X115920Y-104685D01*
X115293Y-105000D01*
X113727D01*
G01X126483D02*
Y-98700D01*
X128442D01*
X129068Y-99015D01*
X129460Y-99435D01*
X129617Y-100275D01*
X129460Y-101115D01*
X128990Y-101640D01*
X128442Y-101955D01*
X126483D01*
G01X128442D02*
X129617Y-105000D01*
G01X132627D02*
Y-98700D01*
X134193D01*
X134820Y-99015D01*
X135290Y-99435D01*
X135682Y-100065D01*
X135995Y-100800D01*
X136073Y-101850D01*
X135995Y-102900D01*
X135682Y-103635D01*
X135290Y-104265D01*
X134820Y-104685D01*
X134193Y-105000D01*
X132627D01*
G01X140650Y-105210D02*
X140493Y-105105D01*
Y-104895D01*
X140650Y-104790D01*
X140807Y-104895D01*
Y-105105D01*
X140650Y-105210D01*
G01X15547Y754608D02*
X18962Y751193D01*
X28854D01*
X32147Y754486D01*
X39476D01*
X54483Y739479D01*
Y679810D01*
G01X7673Y758545D02*
X27788D01*
X30912Y761669D01*
X35717D01*
X41905Y755481D01*
Y754088D01*
X59236Y736757D01*
Y670758D01*
G01X15551Y1278228D02*
Y1281559D01*
X18779Y1284787D01*
Y1292242D01*
X24102Y1297565D01*
X27920D01*
X31970Y1301615D01*
X33880D01*
X36093Y1303828D01*
Y1354519D01*
X46737Y1365163D01*
Y1462698D01*
X42938Y1466497D01*
Y1530301D01*
X70011Y1557374D01*
Y1615372D01*
X17082Y1668301D01*
Y1758228D01*
X10389Y1764921D01*
Y1817222D01*
X16406Y1823239D01*
X39510D01*
X45056Y1817693D01*
G01Y1768087D02*
X52718Y1760425D01*
Y1650269D01*
X93146Y1609841D01*
Y1503574D01*
X53753Y1464181D01*
Y1359812D01*
X43144Y1349203D01*
Y1281164D01*
X40684Y1278704D01*
Y1267841D01*
X36056Y1263213D01*
X30661D01*
X27956Y1265918D01*
X24788D01*
X16415Y1274291D01*
X7677D01*
G01X33267Y1266417D02*
X30281Y1269403D01*
Y1270412D01*
X26372Y1274321D01*
X24890D01*
X20898Y1278313D01*
Y1285936D01*
X24600Y1289638D01*
X27840D01*
X32642Y1294440D01*
X34949D01*
X37493Y1296984D01*
Y1351472D01*
X48137Y1362116D01*
Y1466485D01*
X87546Y1505894D01*
Y1602390D01*
X23402Y1666534D01*
Y1668874D01*
G01Y1718480D02*
X29331Y1712551D01*
Y1674803D01*
X23402Y1668874D01*
G01X33267Y1274291D02*
X41693Y1282717D01*
Y1349732D01*
X52337Y1360376D01*
Y1464745D01*
X91746Y1504154D01*
Y1607423D01*
X50760Y1648409D01*
Y1752424D01*
X35097Y1768087D01*
X23402D01*
G01Y1817693D02*
X16892Y1811183D01*
Y1767278D01*
X33520Y1750650D01*
Y1659322D01*
X88946Y1603896D01*
Y1505314D01*
X49537Y1465905D01*
Y1361536D01*
X38893Y1350892D01*
Y1291054D01*
X34440Y1286601D01*
X32027D01*
X29829Y1284403D01*
Y1282664D01*
X25393Y1278228D01*
G01X64979Y400500D02*
X65272D01*
X69133Y396639D01*
Y387423D01*
X67305Y385595D01*
X62917D01*
X58016Y390496D01*
X52530D01*
X46342Y396684D01*
Y434144D01*
X29249Y451237D01*
Y473374D01*
X78682Y522807D01*
Y553496D01*
X71522Y560656D01*
Y764094D01*
X37701Y797915D01*
X33263D01*
G01X54979Y385500D02*
X44851Y395628D01*
Y433526D01*
X27849Y450528D01*
Y473954D01*
X77282Y523387D01*
Y552916D01*
X70122Y560076D01*
Y763514D01*
X38746Y794890D01*
X31958D01*
X30378Y796470D01*
Y802905D01*
X33263Y805790D01*
G01X64979Y380500D02*
X63930Y379451D01*
X52164D01*
X46167Y385448D01*
Y391958D01*
X42877Y395248D01*
Y432708D01*
X26449Y449136D01*
Y474534D01*
X75882Y523967D01*
Y552336D01*
X68722Y559496D01*
Y762456D01*
X38222Y792956D01*
X31796D01*
X25389Y799363D01*
Y801853D01*
G01Y809727D02*
X34092D01*
X36238Y807581D01*
Y801358D01*
X72922Y764674D01*
Y561236D01*
X80082Y554076D01*
Y522227D01*
X30649Y472794D01*
Y452847D01*
X51225Y432271D01*
Y425835D01*
X47849Y422459D01*
Y404905D01*
X51433Y401321D01*
X56553D01*
X64979Y392895D01*
Y390500D01*
G01X54979Y405500D02*
X52607D01*
X49338Y408769D01*
Y421842D01*
X52714Y425218D01*
Y432888D01*
X32049Y453553D01*
Y472214D01*
X81482Y521647D01*
Y554656D01*
X74322Y561816D01*
Y765254D01*
X37638Y801938D01*
Y809245D01*
X35943Y810940D01*
Y810984D01*
X33263Y813664D01*
G01X54979Y415500D02*
X58414Y418935D01*
Y429736D01*
X33449Y454701D01*
Y471634D01*
X82882Y521067D01*
Y555236D01*
X75722Y562396D01*
Y765834D01*
X39038Y802518D01*
Y810068D01*
X36402Y812704D01*
Y818399D01*
X33263Y821538D01*
G01X64979Y410500D02*
X60084Y415395D01*
Y430175D01*
X34849Y455410D01*
Y471054D01*
X84282Y520487D01*
Y555816D01*
X77122Y562976D01*
Y766414D01*
X40461Y803075D01*
Y810948D01*
X37864Y813545D01*
Y821775D01*
X34611Y825028D01*
X30874D01*
X25389Y819543D01*
Y817601D01*
G01X33263Y750671D02*
X33291Y750699D01*
X40644D01*
X52006Y739337D01*
Y677475D01*
X54154Y675327D01*
X57124D01*
G01X95775Y751469D02*
X94308D01*
X41960Y803817D01*
Y811607D01*
X39400Y814167D01*
Y823409D01*
X36831Y825978D01*
Y830685D01*
X34077Y833439D01*
X31466D01*
X25389Y839516D01*
Y841223D01*
G01X33267Y1282165D02*
X40293Y1289191D01*
Y1350312D01*
X50937Y1360956D01*
Y1465325D01*
X90346Y1504734D01*
Y1605748D01*
X45056Y1651038D01*
Y1668874D01*
G01X70865Y872278D02*
X64404Y878739D01*
Y993349D01*
X70315Y999260D01*
Y1083256D01*
X87998Y1100939D01*
Y1118803D01*
X103676Y1134481D01*
Y1258207D01*
X87836Y1274047D01*
Y1402555D01*
X103152Y1417871D01*
Y1436730D01*
X115172Y1448750D01*
Y1455449D01*
X119920Y1460197D01*
G01Y1808228D02*
X110916Y1799224D01*
X108125D01*
X104972Y1796071D01*
Y1738893D01*
X99746Y1733667D01*
Y1498569D01*
X92369Y1491192D01*
Y1416585D01*
X84486Y1408702D01*
Y1272229D01*
X101992Y1254723D01*
Y1135431D01*
X86247Y1119686D01*
Y1102306D01*
X68210Y1084269D01*
Y1000739D01*
X62559Y995088D01*
Y874584D01*
X70865Y866278D01*
G01X139920Y1102165D02*
X135812Y1106273D01*
X115647D01*
X113365Y1108555D01*
X108032D01*
X104225Y1104748D01*
Y1064756D01*
X84005Y1044536D01*
Y938139D01*
X73940Y928074D01*
Y863353D01*
X70865Y860278D01*
G01X119920Y1112165D02*
X115070D01*
X113731Y1113504D01*
X106752D01*
X100971Y1107723D01*
Y1064463D01*
X82273Y1045765D01*
Y945367D01*
X66750Y929844D01*
Y894231D01*
X70865Y890116D01*
G01X114498Y396207D02*
Y370749D01*
X92644Y348895D01*
Y50589D01*
X101430Y41803D01*
G01X119920Y18071D02*
X110955Y27036D01*
Y40435D01*
X105779Y45611D01*
X101999D01*
X94137Y53473D01*
Y342655D01*
X117584Y366102D01*
X119920D01*
G01X104350Y62293D02*
X96057Y70586D01*
Y334556D01*
X126983Y365482D01*
Y397557D01*
X122481Y402059D01*
X110188D01*
X106725Y405522D01*
X106724D01*
X105451Y406795D01*
G01X139920Y386102D02*
X135472Y390550D01*
Y397616D01*
X122605Y410483D01*
X119263D01*
X115525Y414221D01*
Y420701D01*
X96560Y439666D01*
Y681719D01*
X127826Y712985D01*
Y764031D01*
X123565Y768292D01*
X119390D01*
X91733Y795949D01*
Y899382D01*
G01X105087Y754126D02*
X108755D01*
X112789Y750092D01*
X123016D01*
X125981Y747127D01*
Y713686D01*
X94426Y682131D01*
Y438318D01*
X105451Y427293D01*
Y406795D01*
G01X119920Y714134D02*
Y709605D01*
X92762Y682447D01*
Y436035D01*
X99385Y429412D01*
Y410002D01*
X109163Y400224D01*
X122336D01*
X124709Y397851D01*
Y370891D01*
X119920Y366102D01*
G01X91294Y926951D02*
Y919456D01*
X85443Y913605D01*
Y874267D01*
X87020Y872690D01*
Y766196D01*
X104831Y748385D01*
X121326D01*
X124240Y745471D01*
Y718454D01*
X119920Y714134D01*
G01X105087Y754126D02*
X88420Y770793D01*
Y873964D01*
X86843Y875541D01*
Y910685D01*
X93598Y917440D01*
Y930983D01*
X88606Y935975D01*
Y1016468D01*
X127913Y1055775D01*
Y1091526D01*
X121999Y1097440D01*
X115116D01*
X108779Y1103777D01*
Y1105760D01*
G01X92633Y907404D02*
X93833Y906204D01*
Y803787D01*
X118285Y779335D01*
X122436D01*
X130259Y771512D01*
Y712889D01*
X98160Y680790D01*
Y441462D01*
X118359Y421263D01*
X142230D01*
X144834Y418659D01*
Y371016D01*
X139920Y366102D01*
G01Y714134D02*
X132192Y721862D01*
Y781159D01*
X125217Y788134D01*
X112248D01*
X95433Y804949D01*
Y988253D01*
X98139Y990959D01*
G01X89338Y878294D02*
X89820Y877812D01*
Y791300D01*
X104538Y776582D01*
Y773945D01*
X114349Y764134D01*
X119920D01*
G01X139920Y734134D02*
X135004Y739050D01*
Y780610D01*
X125480Y790134D01*
X113077D01*
X97033Y806178D01*
Y983483D01*
X100687Y987137D01*
Y999391D01*
G01X91294Y926951D02*
Y929029D01*
X86608Y933715D01*
Y1028853D01*
X119920Y1062165D01*
G01X100719Y1324810D02*
X96501Y1329028D01*
Y1386778D01*
X119920Y1410197D01*
G01X107391Y1794460D02*
X109653Y1792198D01*
Y1740517D01*
X101146Y1732010D01*
Y1459231D01*
X95236Y1453321D01*
G01X139920Y38071D02*
X134762Y43229D01*
X115474D01*
X111588Y47115D01*
Y58262D01*
X98097Y71753D01*
Y334332D01*
X135472Y371707D01*
Y381654D01*
X139920Y386102D01*
G01Y18071D02*
X145989Y24140D01*
Y67659D01*
X140417Y73231D01*
X108822D01*
X100071Y81982D01*
Y334042D01*
X132131Y366102D01*
X139920D01*
G01X98139Y990959D02*
Y1020384D01*
X139920Y1062165D01*
G01Y1082165D02*
X145815Y1076270D01*
Y1061919D01*
X100687Y1016791D01*
Y999391D01*
G01X100719Y1306810D02*
X106554Y1312645D01*
Y1382545D01*
X127157Y1403148D01*
X145950D01*
X147431Y1404629D01*
Y1460810D01*
X142714Y1465527D01*
X135546D01*
X124886Y1476187D01*
X116241D01*
X107532Y1484896D01*
Y1726861D01*
X133570Y1752899D01*
X140884D01*
X146654Y1758669D01*
Y1795432D01*
X143858Y1798228D01*
X139920D01*
G01X100719Y1330810D02*
X103071Y1333162D01*
Y1384009D01*
X129259Y1410197D01*
X139920D01*
G01X100719Y1318810D02*
X104880Y1322971D01*
Y1383300D01*
X126187Y1404607D01*
X144565D01*
X145968Y1406010D01*
Y1444149D01*
X139920Y1450197D01*
G01Y1430197D02*
Y1427571D01*
X134785Y1422436D01*
Y1418980D01*
X98179Y1382374D01*
Y1339350D01*
X100719Y1336810D01*
G01X119920Y1758228D02*
X111262Y1749570D01*
Y1739326D01*
X102546Y1730610D01*
Y1478433D01*
X116701Y1464278D01*
X121496D01*
X126015Y1459759D01*
Y1416292D01*
X119920Y1410197D01*
G01X139920D02*
X144359Y1414636D01*
Y1433492D01*
X142371Y1435480D01*
X138108D01*
X134769Y1438819D01*
Y1461649D01*
X122004Y1474414D01*
X114429D01*
X105746Y1483097D01*
Y1728000D01*
X135974Y1758228D01*
X139920D01*
G01Y1778228D02*
X135648Y1773956D01*
Y1760550D01*
X104146Y1729048D01*
Y1479747D01*
X117764Y1466129D01*
X122806D01*
X130375Y1458560D01*
Y1439742D01*
X139920Y1430197D01*
G01X202000Y-72000D02*
Y-80000D01*
X206000D01*
G01X213800D02*
Y-74667D01*
G01Y-75600D02*
X213400Y-75067D01*
X212800Y-74800D01*
X212100Y-74667D01*
X211400Y-74933D01*
X210800Y-75467D01*
X210400Y-76267D01*
X210200Y-77333D01*
X210400Y-78400D01*
X210800Y-79200D01*
X211400Y-79733D01*
X212100Y-80000D01*
X212800Y-79867D01*
X213400Y-79467D01*
X213800Y-78934D01*
G01X217900Y-82400D02*
X218500Y-82667D01*
X219300Y-82400D01*
X219800Y-81867D01*
X220200Y-81200D01*
X220800Y-79067D01*
X222100Y-74667D01*
G01X218900D02*
X220800Y-79067D01*
G01X226500Y-76400D02*
X229700D01*
X229400Y-75467D01*
X228900Y-74933D01*
X228200Y-74667D01*
X227500Y-74800D01*
X226900Y-75200D01*
X226500Y-76133D01*
X226300Y-76934D01*
Y-77733D01*
X226500Y-78533D01*
X227000Y-79333D01*
X227600Y-79867D01*
X228300Y-80000D01*
X229000Y-79733D01*
X229700Y-78934D01*
G01X234600Y-80000D02*
Y-74667D01*
G01Y-75733D02*
X235100Y-75200D01*
X235600Y-74800D01*
X236300Y-74667D01*
X236800Y-74800D01*
X237400Y-75200D01*
G01X225500Y-122000D02*
Y-130000D01*
G01X223200Y-122000D02*
X227800D01*
G01X233500Y-124667D02*
Y-130000D01*
G01Y-122533D02*
X233300Y-122400D01*
Y-122133D01*
X233500Y-122000D01*
X233700Y-122133D01*
Y-122400D01*
X233500Y-122533D01*
G01X239800Y-130000D02*
Y-124667D01*
G01Y-126000D02*
X240200Y-125333D01*
X240800Y-124800D01*
X241600Y-124667D01*
X242300Y-124800D01*
X242900Y-125333D01*
X243200Y-126267D01*
Y-130000D01*
G01X251300D02*
Y-124667D01*
G01Y-125600D02*
X250900Y-125067D01*
X250300Y-124800D01*
X249600Y-124667D01*
X248900Y-124933D01*
X248300Y-125467D01*
X247900Y-126267D01*
X247700Y-127333D01*
X247900Y-128400D01*
X248300Y-129200D01*
X248900Y-129733D01*
X249600Y-130000D01*
X250300Y-129867D01*
X250900Y-129467D01*
X251300Y-128934D01*
G01X226300Y-100733D02*
X226700Y-100333D01*
X227000Y-99667D01*
X227200Y-98733D01*
X227000Y-97933D01*
X226600Y-97400D01*
X225900Y-97000D01*
X223200D01*
Y-105000D01*
X226500D01*
X227200Y-104467D01*
X227600Y-103667D01*
X227800Y-102733D01*
X227600Y-101800D01*
X227000Y-101000D01*
X226300Y-100733D01*
X223200D01*
G01X233500Y-105000D02*
X232700Y-104867D01*
X232000Y-104333D01*
X231400Y-103533D01*
X231000Y-102600D01*
X230800Y-101533D01*
Y-100467D01*
X231000Y-99400D01*
X231400Y-98467D01*
X232000Y-97667D01*
X232700Y-97133D01*
X233500Y-97000D01*
X234300Y-97133D01*
X235000Y-97667D01*
X235600Y-98467D01*
X236000Y-99400D01*
X236200Y-100467D01*
Y-101533D01*
X236000Y-102600D01*
X235600Y-103533D01*
X235000Y-104333D01*
X234300Y-104867D01*
X233500Y-105000D01*
G01X241500Y-97000D02*
Y-105000D01*
G01X239200Y-97000D02*
X243800D01*
G01X249500D02*
Y-105000D01*
G01X247200Y-97000D02*
X251800D01*
G01X257500Y-105000D02*
X256700Y-104867D01*
X256000Y-104333D01*
X255400Y-103533D01*
X255000Y-102600D01*
X254800Y-101533D01*
Y-100467D01*
X255000Y-99400D01*
X255400Y-98467D01*
X256000Y-97667D01*
X256700Y-97133D01*
X257500Y-97000D01*
X258300Y-97133D01*
X259000Y-97667D01*
X259600Y-98467D01*
X260000Y-99400D01*
X260200Y-100467D01*
Y-101533D01*
X260000Y-102600D01*
X259600Y-103533D01*
X259000Y-104333D01*
X258300Y-104867D01*
X257500Y-105000D01*
G01X262900D02*
Y-97000D01*
X265500Y-103667D01*
X268100Y-97000D01*
Y-105000D01*
G01X255500Y-80000D02*
X256200Y-79867D01*
X257000Y-79467D01*
X257500Y-78800D01*
X257700Y-77867D01*
X257500Y-76934D01*
X256900Y-76133D01*
X256000Y-75733D01*
X255000D01*
X254400Y-75467D01*
X253900Y-74800D01*
X253700Y-73867D01*
X254000Y-72933D01*
X254700Y-72267D01*
X255500Y-72000D01*
X256300Y-72267D01*
X257000Y-72933D01*
X257300Y-73867D01*
X257100Y-74800D01*
X256600Y-75467D01*
X256000Y-75733D01*
X255000D01*
X254100Y-76133D01*
X253500Y-76934D01*
X253300Y-77867D01*
X253500Y-78800D01*
X254000Y-79467D01*
X254800Y-79867D01*
X255500Y-80000D01*
G01X328600Y-123333D02*
X329200Y-122533D01*
X329900Y-122133D01*
X330700Y-122000D01*
X331700Y-122267D01*
X332400Y-122933D01*
X332600Y-123733D01*
X332500Y-124534D01*
X332100Y-125200D01*
X330100Y-126533D01*
X329200Y-127467D01*
X328600Y-128800D01*
X328400Y-130000D01*
X332600D01*
G01X338500Y-122000D02*
X337700Y-122267D01*
X337100Y-122933D01*
X336700Y-123733D01*
X336400Y-124800D01*
X336300Y-126000D01*
X336400Y-127200D01*
X336700Y-128267D01*
X337100Y-129067D01*
X337700Y-129733D01*
X338500Y-130000D01*
X339300Y-129733D01*
X339900Y-129067D01*
X340300Y-128267D01*
X340600Y-127200D01*
X340700Y-126000D01*
X340600Y-124800D01*
X340300Y-123733D01*
X339900Y-122933D01*
X339300Y-122267D01*
X338500Y-122000D01*
G01X346500Y-130000D02*
Y-122000D01*
X345300Y-123600D01*
G01Y-130000D02*
X347700D01*
G01X352300Y-128400D02*
X352900Y-129333D01*
X353700Y-129867D01*
X354600Y-130000D01*
X355400Y-129867D01*
X356200Y-129200D01*
X356700Y-128400D01*
X356800Y-127600D01*
X356600Y-126667D01*
X355900Y-126000D01*
X355200Y-125733D01*
X354300D01*
G01X355200D02*
X355800Y-125333D01*
X356300Y-124667D01*
X356500Y-123867D01*
X356300Y-123067D01*
X355800Y-122400D01*
X354900Y-122000D01*
X354000Y-122133D01*
X353100Y-122667D01*
G01X360700Y-130267D02*
X364300Y-122000D01*
G01X370500D02*
X369700Y-122267D01*
X369100Y-122933D01*
X368700Y-123733D01*
X368400Y-124800D01*
X368300Y-126000D01*
X368400Y-127200D01*
X368700Y-128267D01*
X369100Y-129067D01*
X369700Y-129733D01*
X370500Y-130000D01*
X371300Y-129733D01*
X371900Y-129067D01*
X372300Y-128267D01*
X372600Y-127200D01*
X372700Y-126000D01*
X372600Y-124800D01*
X372300Y-123733D01*
X371900Y-122933D01*
X371300Y-122267D01*
X370500Y-122000D01*
G01X378500Y-130000D02*
Y-122000D01*
X377300Y-123600D01*
G01Y-130000D02*
X379700D01*
G01X384700Y-130267D02*
X388300Y-122000D01*
G01X394500D02*
X393700Y-122267D01*
X393100Y-122933D01*
X392700Y-123733D01*
X392400Y-124800D01*
X392300Y-126000D01*
X392400Y-127200D01*
X392700Y-128267D01*
X393100Y-129067D01*
X393700Y-129733D01*
X394500Y-130000D01*
X395300Y-129733D01*
X395900Y-129067D01*
X396300Y-128267D01*
X396600Y-127200D01*
X396700Y-126000D01*
X396600Y-124800D01*
X396300Y-123733D01*
X395900Y-122933D01*
X395300Y-122267D01*
X394500Y-122000D01*
G01X400800Y-129067D02*
X401500Y-129733D01*
X402300Y-130000D01*
X403100Y-129733D01*
X403800Y-128934D01*
X404300Y-127733D01*
X404500Y-126533D01*
Y-125067D01*
X404300Y-123867D01*
X403800Y-122800D01*
X403200Y-122267D01*
X402500Y-122000D01*
X401700Y-122267D01*
X401100Y-122800D01*
X400700Y-123600D01*
X400500Y-124667D01*
X400700Y-125600D01*
X401200Y-126533D01*
X401800Y-127067D01*
X402500Y-127200D01*
X403300Y-126934D01*
X403900Y-126267D01*
X404500Y-125067D01*
G01X328300Y-105000D02*
Y-97000D01*
X330300D01*
X331100Y-97400D01*
X331700Y-97933D01*
X332200Y-98733D01*
X332600Y-99667D01*
X332700Y-101000D01*
X332600Y-102333D01*
X332200Y-103267D01*
X331700Y-104067D01*
X331100Y-104600D01*
X330300Y-105000D01*
X328300D01*
G01X336000D02*
X338500Y-97000D01*
X341000Y-105000D01*
G01X340100Y-102200D02*
X336900D01*
G01X346500Y-97000D02*
Y-105000D01*
G01X344200Y-97000D02*
X348800D01*
G01X352600Y-101667D02*
X353300Y-100733D01*
X353900Y-100200D01*
X354700Y-99933D01*
X355400Y-100200D01*
X355900Y-100733D01*
X356300Y-101533D01*
X356400Y-102467D01*
X356300Y-103267D01*
X355900Y-104067D01*
X355300Y-104733D01*
X354600Y-105000D01*
X353800Y-104733D01*
X353100Y-103934D01*
X352700Y-102733D01*
X352600Y-101400D01*
X352800Y-99667D01*
X353100Y-98733D01*
X353600Y-97800D01*
X354300Y-97133D01*
X355000Y-97000D01*
X355700Y-97267D01*
X356200Y-97933D01*
G01X359900Y-105000D02*
Y-97000D01*
X362500Y-103667D01*
X365100Y-97000D01*
Y-105000D01*
G01X370500Y-97000D02*
Y-105000D01*
G01X368200Y-97000D02*
X372800D01*
G01X379300Y-100733D02*
X379700Y-100333D01*
X380000Y-99667D01*
X380200Y-98733D01*
X380000Y-97933D01*
X379600Y-97400D01*
X378900Y-97000D01*
X376200D01*
Y-105000D01*
X379500D01*
X380200Y-104467D01*
X380600Y-103667D01*
X380800Y-102733D01*
X380600Y-101800D01*
X380000Y-101000D01*
X379300Y-100733D01*
X376200D01*
G01X386500Y-105000D02*
X387200Y-104867D01*
X388000Y-104467D01*
X388500Y-103800D01*
X388700Y-102867D01*
X388500Y-101934D01*
X387900Y-101133D01*
X387000Y-100733D01*
X386000D01*
X385400Y-100467D01*
X384900Y-99800D01*
X384700Y-98867D01*
X385000Y-97933D01*
X385700Y-97267D01*
X386500Y-97000D01*
X387300Y-97267D01*
X388000Y-97933D01*
X388300Y-98867D01*
X388100Y-99800D01*
X387600Y-100467D01*
X387000Y-100733D01*
X386000D01*
X385100Y-101133D01*
X384500Y-101934D01*
X384300Y-102867D01*
X384500Y-103800D01*
X385000Y-104467D01*
X385800Y-104867D01*
X386500Y-105000D01*
G01X394500D02*
X395200Y-104867D01*
X396000Y-104467D01*
X396500Y-103800D01*
X396700Y-102867D01*
X396500Y-101934D01*
X395900Y-101133D01*
X395000Y-100733D01*
X394000D01*
X393400Y-100467D01*
X392900Y-99800D01*
X392700Y-98867D01*
X393000Y-97933D01*
X393700Y-97267D01*
X394500Y-97000D01*
X395300Y-97267D01*
X396000Y-97933D01*
X396300Y-98867D01*
X396100Y-99800D01*
X395600Y-100467D01*
X395000Y-100733D01*
X394000D01*
X393100Y-101133D01*
X392500Y-101934D01*
X392300Y-102867D01*
X392500Y-103800D01*
X393000Y-104467D01*
X393800Y-104867D01*
X394500Y-105000D01*
G01X400000D02*
X402500Y-97000D01*
X405000Y-105000D01*
G01X404100Y-102200D02*
X400900D01*
G01X410500Y-97000D02*
X409700Y-97267D01*
X409100Y-97933D01*
X408700Y-98733D01*
X408400Y-99800D01*
X408300Y-101000D01*
X408400Y-102200D01*
X408700Y-103267D01*
X409100Y-104067D01*
X409700Y-104733D01*
X410500Y-105000D01*
X411300Y-104733D01*
X411900Y-104067D01*
X412300Y-103267D01*
X412600Y-102200D01*
X412700Y-101000D01*
X412600Y-99800D01*
X412300Y-98733D01*
X411900Y-97933D01*
X411300Y-97267D01*
X410500Y-97000D01*
G01X352165Y29705D02*
Y38656D01*
X348605Y42216D01*
X330978D01*
X326171Y47023D01*
Y56973D01*
X333704Y64506D01*
Y90105D01*
X384318Y140719D01*
Y275736D01*
X371610Y288444D01*
Y297386D01*
X373942Y299718D01*
Y300523D01*
G01X352165Y19705D02*
Y24815D01*
X348607Y28373D01*
Y31153D01*
X350508Y33054D01*
Y38320D01*
X348021Y40807D01*
X330394D01*
X324762Y46439D01*
Y57557D01*
X332295Y65090D01*
Y90689D01*
X382909Y141303D01*
Y275152D01*
X370201Y287860D01*
Y298813D01*
X368544Y300470D01*
G01X352165Y194705D02*
Y200063D01*
X348972Y203256D01*
Y206765D01*
X350692Y208485D01*
Y212435D01*
X335916Y227211D01*
Y268970D01*
X358555Y291609D01*
Y298232D01*
X356831Y299956D01*
G01X352165Y204705D02*
Y213082D01*
X337415Y227832D01*
Y268349D01*
X360054Y290988D01*
Y297207D01*
X362227Y299380D01*
G01X364353Y650514D02*
X358965Y645126D01*
X351492D01*
X336103Y629737D01*
Y605608D01*
X324835Y594340D01*
Y582490D01*
X344472Y562853D01*
X349449D01*
X352166Y560136D01*
Y554705D01*
G01X358911Y650530D02*
X356306Y647925D01*
X351372D01*
X334525Y631078D01*
Y606262D01*
X323257Y594994D01*
Y581836D01*
X343158Y561935D01*
Y558646D01*
X352166Y549638D01*
Y544705D01*
G01X352165Y1779705D02*
Y1789166D01*
X336329Y1805002D01*
Y1855741D01*
X353250Y1872662D01*
Y1874308D01*
G01X352165Y1769705D02*
Y1775305D01*
X348606Y1778864D01*
Y1781753D01*
X350727Y1783874D01*
Y1788299D01*
X334929Y1804097D01*
Y1856321D01*
X347105Y1868497D01*
Y1875191D01*
G01X350500Y-72000D02*
Y-80000D01*
G01X348200Y-72000D02*
X352800D01*
G01X356600Y-76667D02*
X357300Y-75733D01*
X357900Y-75200D01*
X358700Y-74933D01*
X359400Y-75200D01*
X359900Y-75733D01*
X360300Y-76533D01*
X360400Y-77467D01*
X360300Y-78267D01*
X359900Y-79067D01*
X359300Y-79733D01*
X358600Y-80000D01*
X357800Y-79733D01*
X357100Y-78934D01*
X356700Y-77733D01*
X356600Y-76400D01*
X356800Y-74667D01*
X357100Y-73733D01*
X357600Y-72800D01*
X358300Y-72133D01*
X359000Y-72000D01*
X359700Y-72267D01*
X360200Y-72933D01*
G01X363900Y-80000D02*
Y-72000D01*
X366500Y-78667D01*
X369100Y-72000D01*
Y-80000D01*
G01X375100Y-76000D02*
X377100D01*
Y-78400D01*
X376500Y-79200D01*
X375800Y-79733D01*
X374800Y-80000D01*
X373800Y-79733D01*
X373100Y-79200D01*
X372500Y-78400D01*
X372100Y-77467D01*
X371900Y-76400D01*
Y-75467D01*
X372100Y-74667D01*
X372500Y-73733D01*
X373100Y-72933D01*
X373700Y-72400D01*
X374500Y-72000D01*
X375200D01*
X376000Y-72267D01*
X376600Y-72800D01*
G01X379500Y-82667D02*
X385500D01*
G01X388500Y-80000D02*
Y-72000D01*
X390900D01*
X391700Y-72400D01*
X392300Y-73333D01*
X392500Y-74400D01*
X392300Y-75467D01*
X391800Y-76267D01*
X390900Y-76667D01*
X388500D01*
G01X396300Y-80000D02*
Y-72000D01*
X398300D01*
X399100Y-72400D01*
X399700Y-72933D01*
X400200Y-73733D01*
X400600Y-74667D01*
X400700Y-76000D01*
X400600Y-77333D01*
X400200Y-78267D01*
X399700Y-79067D01*
X399100Y-79600D01*
X398300Y-80000D01*
X396300D01*
G01X407300Y-75733D02*
X407700Y-75333D01*
X408000Y-74667D01*
X408200Y-73733D01*
X408000Y-72933D01*
X407600Y-72400D01*
X406900Y-72000D01*
X404200D01*
Y-80000D01*
X407500D01*
X408200Y-79467D01*
X408600Y-78667D01*
X408800Y-77733D01*
X408600Y-76800D01*
X408000Y-76000D01*
X407300Y-75733D01*
X404200D01*
G01X411500Y-82667D02*
X417500D01*
G01X420000Y-80000D02*
X422500Y-72000D01*
X425000Y-80000D01*
G01X424100Y-77200D02*
X420900D01*
G01X427500Y-82667D02*
X433500D01*
G01X439300Y-75733D02*
X439700Y-75333D01*
X440000Y-74667D01*
X440200Y-73733D01*
X440000Y-72933D01*
X439600Y-72400D01*
X438900Y-72000D01*
X436200D01*
Y-80000D01*
X439500D01*
X440200Y-79467D01*
X440600Y-78667D01*
X440800Y-77733D01*
X440600Y-76800D01*
X440000Y-76000D01*
X439300Y-75733D01*
X436200D01*
G01X444300Y-80000D02*
Y-72000D01*
X446300D01*
X447100Y-72400D01*
X447700Y-72933D01*
X448200Y-73733D01*
X448600Y-74667D01*
X448700Y-76000D01*
X448600Y-77333D01*
X448200Y-78267D01*
X447700Y-79067D01*
X447100Y-79600D01*
X446300Y-80000D01*
X444300D01*
G01X362227Y299380D02*
X360936Y300671D01*
Y302825D01*
X362236Y304125D01*
Y306891D01*
G01X359677Y329891D02*
Y312794D01*
X357456Y310573D01*
Y300581D01*
X356831Y299956D01*
G01X367477Y324983D02*
X362236D01*
G01D02*
Y329891D01*
G01X360533Y339095D02*
X362812Y341374D01*
Y344422D01*
X351093Y356141D01*
Y363871D01*
X348459Y366505D01*
Y370673D01*
X352165Y374379D01*
Y379705D01*
G01X360533Y339095D02*
Y337370D01*
X364795Y333108D01*
Y329891D01*
G01X367076Y340100D02*
Y343421D01*
X352738Y357759D01*
Y369132D01*
X352165Y369705D01*
G01X359118Y656986D02*
Y661363D01*
X359870Y662115D01*
X361662D01*
G01X361677Y656986D02*
Y653296D01*
X358911Y650530D01*
G01X347227Y694078D02*
X349680Y691625D01*
Y670489D01*
X356559Y663610D01*
Y656986D01*
G01X364112Y662115D02*
X361662D01*
G01D02*
X361745Y662198D01*
Y674406D01*
G01D02*
X357320D01*
X356559Y675167D01*
G01D02*
Y679986D01*
G01X361677D02*
Y674474D01*
X361745Y674406D01*
G01X366795Y679986D02*
Y675045D01*
X366156Y674406D01*
X361745D01*
G01X354000Y679986D02*
Y696721D01*
X352358Y698363D01*
G01X362531Y694417D02*
X361034Y692920D01*
Y687039D01*
X359118Y685123D01*
Y679986D01*
G01X347227Y694078D02*
Y720000D01*
X352166Y724939D01*
Y729705D01*
G01X352358Y698363D02*
X350738Y699983D01*
Y718277D01*
X352166Y719705D01*
G01X362531Y694417D02*
X364880D01*
X370653Y700190D01*
Y713492D01*
X384937Y727776D01*
Y753339D01*
X392217Y760619D01*
Y851842D01*
X354891Y889168D01*
X350951D01*
X348313Y891806D01*
Y895829D01*
X351312Y898828D01*
Y903852D01*
X352165Y904705D01*
G01X368680Y694668D02*
X372313Y698301D01*
Y713172D01*
X386337Y727196D01*
Y752759D01*
X393617Y760039D01*
Y852422D01*
X355881Y890158D01*
Y890989D01*
X352165Y894705D01*
G01Y1069705D02*
Y1074686D01*
X348168Y1078683D01*
Y1080585D01*
X351131Y1083548D01*
Y1088082D01*
X355811Y1092762D01*
X362101D01*
X384336Y1114997D01*
Y1141840D01*
X361643Y1164533D01*
Y1213425D01*
X384849Y1236631D01*
Y1328425D01*
X381725Y1331549D01*
Y1340790D01*
G01X385261Y1334686D02*
Y1330399D01*
X386348Y1329312D01*
Y1236010D01*
X363142Y1212804D01*
Y1165154D01*
X385835Y1142461D01*
Y1114376D01*
X362722Y1091263D01*
X356432D01*
X352776Y1087607D01*
Y1080316D01*
X352165Y1079705D01*
G01Y1254705D02*
X353434Y1255974D01*
Y1264973D01*
X357310Y1268849D01*
X362796D01*
X383423Y1289476D01*
Y1322207D01*
X381521Y1324109D01*
Y1329307D01*
X378904Y1331924D01*
Y1333844D01*
G01X373499Y1340730D02*
X376688Y1337541D01*
Y1332065D01*
X380058Y1328695D01*
Y1323503D01*
X381960Y1321601D01*
Y1290082D01*
X362190Y1270312D01*
X356704D01*
X351752Y1265360D01*
Y1259341D01*
X348094Y1255683D01*
Y1253490D01*
X352165Y1249419D01*
Y1244705D01*
G01X377984Y1383142D02*
X378851Y1384009D01*
Y1386167D01*
X348570Y1416448D01*
Y1421715D01*
X352165Y1425310D01*
Y1429705D01*
G01X380378Y1377228D02*
Y1386800D01*
X351442Y1415736D01*
Y1418982D01*
X352165Y1419705D01*
G01Y1594705D02*
X350581Y1596289D01*
Y1601095D01*
X348825Y1602851D01*
Y1605994D01*
X350326Y1607495D01*
Y1612585D01*
X382095Y1644354D01*
Y1847189D01*
X363378Y1865906D01*
Y1873345D01*
X361039Y1875684D01*
G01X365922Y1870477D02*
Y1865342D01*
X383495Y1847769D01*
Y1643774D01*
X351745Y1612024D01*
Y1605125D01*
X352165Y1604705D01*
G01X360236Y1899864D02*
Y1892477D01*
X361478Y1891235D01*
Y1887650D01*
G01X367337Y1882006D02*
Y1886618D01*
X366305Y1887650D01*
X361478D01*
G01D02*
X357968D01*
X357101Y1886783D01*
Y1882006D01*
G01X362219D02*
Y1884898D01*
X361478Y1885639D01*
Y1887650D01*
G01X361039Y1875684D02*
X359660Y1877063D01*
Y1882006D01*
G01X353250Y1874308D02*
Y1876703D01*
X354542Y1877995D01*
Y1882006D01*
G01X347105Y1875191D02*
X349301Y1877387D01*
Y1892953D01*
X351983Y1895635D01*
Y1905006D01*
G01X359660D02*
Y1901904D01*
X360236Y1901328D01*
Y1899864D01*
G01X354542Y1905006D02*
Y1900891D01*
X355569Y1899864D01*
X360236D01*
G01X366306D02*
X360236D01*
G01X357101Y1905006D02*
Y1910830D01*
X353726Y1914205D01*
G01X352165Y1954705D02*
Y1950137D01*
X348386Y1946358D01*
Y1943945D01*
X353726Y1938605D01*
Y1914205D01*
G01X362219Y1905006D02*
Y1910310D01*
X360118Y1912411D01*
G01D02*
X355274Y1917255D01*
Y1941596D01*
X352165Y1944705D01*
G01X367549Y312720D02*
X369890D01*
G01D02*
X374044D01*
X375031Y311733D01*
Y306891D01*
G01X367549Y312720D02*
X365395D01*
X364795Y312120D01*
Y306891D01*
G01X369913D02*
Y312697D01*
X369890Y312720D01*
G01X367477Y324983D02*
Y312792D01*
X367549Y312720D01*
G01X372472Y306891D02*
Y301993D01*
X373942Y300523D01*
G01X367354Y306891D02*
Y303407D01*
X368544Y302217D01*
Y300470D01*
G01X367354Y329891D02*
Y325106D01*
X367477Y324983D01*
G01X372472Y329891D02*
Y325897D01*
X371558Y324983D01*
X367477D01*
G01X380915Y333668D02*
X373636D01*
X372472Y332504D01*
Y329891D01*
G01X367076Y340100D02*
Y335842D01*
X369913Y333005D01*
Y329891D01*
G01X364236Y656986D02*
Y661991D01*
X364112Y662115D01*
G01X369354Y656986D02*
Y661152D01*
X368391Y662115D01*
X364112D01*
G01X364353Y650514D02*
Y651277D01*
X366795Y653719D01*
Y656986D01*
G01X364236Y679986D02*
Y688325D01*
X368680Y692769D01*
Y694668D01*
G01X385261Y1334686D02*
Y1337506D01*
X384040Y1338727D01*
Y1343463D01*
X384917Y1344340D01*
Y1347255D01*
G01X378904Y1333844D02*
Y1339237D01*
X374681Y1343460D01*
Y1347255D01*
G01X382560Y1353098D02*
Y1364505D01*
X382412Y1364653D01*
G01X387476Y1347255D02*
Y1351437D01*
X385815Y1353098D01*
X382560D01*
G01D02*
X378318D01*
X377240Y1352020D01*
Y1347255D01*
G01X382358D02*
Y1352896D01*
X382560Y1353098D01*
G01X381725Y1340790D02*
Y1342663D01*
X379799Y1344589D01*
Y1347255D01*
G01X372122Y1370255D02*
Y1366417D01*
X369931Y1364226D01*
Y1344298D01*
X373499Y1340730D01*
G01X384917Y1370255D02*
Y1365584D01*
X383986Y1364653D01*
X382412D01*
G01X374681Y1370255D02*
Y1365620D01*
G01D02*
X375648Y1364653D01*
X379805D01*
G01X379799Y1370255D02*
Y1364659D01*
X379805Y1364653D01*
G01X382412D02*
X379805D01*
G01X377240Y1370255D02*
Y1373469D01*
X377984Y1374213D01*
Y1383142D01*
G01X382358Y1370255D02*
Y1373727D01*
X380378Y1375707D01*
Y1377228D01*
G01X364778Y1882006D02*
Y1871621D01*
X365922Y1870477D01*
G01X366306Y1899864D02*
Y1900925D01*
X364778Y1902453D01*
Y1905006D01*
G01X443000Y-130000D02*
X445500Y-122000D01*
X448000Y-130000D01*
G01X447100Y-127200D02*
X443900D01*
G01X473000Y-130000D02*
Y-122000D01*
X471800Y-123600D01*
G01Y-130000D02*
X474200D01*
G01X479100Y-126667D02*
X479800Y-125733D01*
X480400Y-125200D01*
X481200Y-124933D01*
X481900Y-125200D01*
X482400Y-125733D01*
X482800Y-126533D01*
X482900Y-127467D01*
X482800Y-128267D01*
X482400Y-129067D01*
X481800Y-129733D01*
X481100Y-130000D01*
X480300Y-129733D01*
X479600Y-128934D01*
X479200Y-127733D01*
X479100Y-126400D01*
X479300Y-124667D01*
X479600Y-123733D01*
X480100Y-122800D01*
X480800Y-122133D01*
X481500Y-122000D01*
X482200Y-122267D01*
X482700Y-122933D01*
G54D34*
X307086Y308267D03*
G54D16*
G01X389940Y333220D02*
Y339095D01*
X386638Y342397D01*
Y657303D01*
X378752Y665189D01*
G01X369676Y688003D02*
X375701Y694028D01*
Y710987D01*
X389817Y725103D01*
Y751248D01*
X397413Y758844D01*
Y858182D01*
X384372Y871223D01*
Y1108136D01*
X389028Y1112792D01*
Y1144460D01*
X366317Y1167171D01*
Y1210431D01*
X389916Y1234030D01*
Y1338399D01*
X391395Y1339878D01*
Y1362340D01*
G01X374431Y1901397D02*
Y1895865D01*
X372061Y1893495D01*
Y1864389D01*
X388017Y1848433D01*
Y1382366D01*
X15547Y707364D03*
X25389D03*
X7673Y703427D03*
X15547Y715238D03*
Y723112D03*
Y730986D03*
X25389Y715238D03*
Y723112D03*
Y730986D03*
X7673Y711301D03*
Y719175D03*
Y727049D03*
X15547Y738860D03*
Y746734D03*
Y754608D03*
X25389Y738860D03*
Y746734D03*
Y754608D03*
X7673Y734923D03*
Y742797D03*
Y750671D03*
Y758545D03*
X15547Y762483D03*
Y770357D03*
Y778231D03*
X25389Y762483D03*
Y770357D03*
Y778231D03*
X7673Y766419D03*
Y774293D03*
Y782167D03*
X15547Y786105D03*
Y793979D03*
Y801853D03*
X25389Y786105D03*
Y793979D03*
Y801853D03*
X7673Y790041D03*
Y797915D03*
Y805790D03*
X15547Y809727D03*
Y817601D03*
Y825475D03*
X25389Y809727D03*
Y817601D03*
Y825475D03*
X7673Y813664D03*
Y821538D03*
Y829412D03*
X15547Y833349D03*
Y841223D03*
Y849097D03*
X25389Y833349D03*
Y841223D03*
Y849097D03*
X7673Y837286D03*
Y845160D03*
Y853034D03*
X15547Y856971D03*
Y864845D03*
Y872719D03*
X25389Y856971D03*
Y864845D03*
Y872719D03*
X7673Y860908D03*
Y868782D03*
Y876656D03*
X15547Y880593D03*
Y888467D03*
Y896341D03*
X25389Y880593D03*
Y888467D03*
Y896341D03*
X7673Y884530D03*
Y892404D03*
Y900278D03*
X15547Y904215D03*
Y912089D03*
Y919963D03*
X25389Y904215D03*
Y912089D03*
Y919963D03*
X7673Y908152D03*
Y916026D03*
Y923900D03*
X15547Y927837D03*
Y935711D03*
Y943585D03*
Y951459D03*
X25389Y927837D03*
Y935711D03*
Y943585D03*
Y951459D03*
X7673Y931774D03*
Y939648D03*
Y947522D03*
X15547Y959333D03*
Y967207D03*
Y975081D03*
X25389Y959333D03*
Y967207D03*
Y975081D03*
X7673Y955396D03*
Y963270D03*
Y971144D03*
Y979018D03*
Y994766D03*
X15547Y990829D03*
Y998703D03*
X25389Y990829D03*
Y998703D03*
X7673Y1002640D03*
Y1010514D03*
Y1018388D03*
X15547Y1006577D03*
Y1014451D03*
Y1022325D03*
X25389Y1006577D03*
Y1014451D03*
Y1022325D03*
X7673Y1026262D03*
X15547Y1030199D03*
X15551Y1065629D03*
X25393D03*
X7677Y1061692D03*
Y1069566D03*
X15551Y1073503D03*
Y1081377D03*
Y1089251D03*
X25393Y1073503D03*
Y1081377D03*
Y1089251D03*
X7677Y1077440D03*
Y1085314D03*
Y1093188D03*
X15551Y1097125D03*
Y1104999D03*
Y1112873D03*
Y1120748D03*
X25393Y1097125D03*
Y1104999D03*
Y1112873D03*
Y1120748D03*
X7677Y1101062D03*
Y1108936D03*
Y1116810D03*
X15551Y1128622D03*
Y1136496D03*
Y1144370D03*
X25393Y1128622D03*
Y1136496D03*
Y1144370D03*
X7677Y1124684D03*
Y1132558D03*
Y1140432D03*
X15551Y1152244D03*
Y1160118D03*
Y1167992D03*
X25393Y1152244D03*
Y1160118D03*
Y1167992D03*
X7677Y1148306D03*
Y1156180D03*
Y1164055D03*
X15551Y1175866D03*
Y1183740D03*
Y1191614D03*
X25393Y1175866D03*
Y1183740D03*
Y1191614D03*
X7677Y1171929D03*
Y1179803D03*
Y1187677D03*
X15551Y1199488D03*
Y1207362D03*
Y1215236D03*
X25393Y1199488D03*
Y1207362D03*
Y1215236D03*
X7677Y1195551D03*
Y1203425D03*
Y1211299D03*
X15551Y1223110D03*
Y1230984D03*
Y1238858D03*
X25393Y1223110D03*
Y1230984D03*
Y1238858D03*
X7677Y1219173D03*
Y1227047D03*
Y1234921D03*
X15551Y1246732D03*
Y1254606D03*
Y1262480D03*
X25393Y1246732D03*
Y1254606D03*
Y1262480D03*
X7677Y1242795D03*
Y1250669D03*
Y1258543D03*
X15551Y1270354D03*
Y1278228D03*
Y1286102D03*
X25393Y1270354D03*
Y1278228D03*
Y1286102D03*
X7677Y1266417D03*
Y1274291D03*
Y1282165D03*
X15551Y1293976D03*
Y1301850D03*
Y1309724D03*
X25393Y1293976D03*
Y1301850D03*
Y1309724D03*
X7677Y1290039D03*
Y1297913D03*
Y1305787D03*
Y1313661D03*
X15551Y1317598D03*
Y1325472D03*
Y1333346D03*
X25393Y1317598D03*
Y1325472D03*
Y1333346D03*
X7677Y1321535D03*
Y1329409D03*
Y1337283D03*
Y1353031D03*
Y1360905D03*
X15551Y1349094D03*
Y1356968D03*
X25393Y1349094D03*
Y1356968D03*
X7677Y1368779D03*
Y1376653D03*
Y1384527D03*
X15551Y1364842D03*
Y1372716D03*
Y1380590D03*
X25393Y1364842D03*
Y1372716D03*
Y1380590D03*
X15551Y1388464D03*
X33263Y703427D03*
Y711301D03*
Y719175D03*
Y727049D03*
Y734923D03*
Y742797D03*
Y750671D03*
Y758545D03*
Y766419D03*
Y774293D03*
Y782167D03*
Y790041D03*
Y797915D03*
Y805790D03*
Y813664D03*
Y821538D03*
Y829412D03*
Y837286D03*
Y845160D03*
Y853034D03*
Y860908D03*
Y868782D03*
Y876656D03*
Y884530D03*
Y892404D03*
Y900278D03*
Y908152D03*
Y916026D03*
Y923900D03*
Y931774D03*
Y939648D03*
Y947522D03*
Y955396D03*
Y963270D03*
Y971144D03*
Y979018D03*
Y994766D03*
Y1002640D03*
Y1010514D03*
Y1018388D03*
Y1026262D03*
X33267Y1061692D03*
Y1069566D03*
Y1077440D03*
Y1085314D03*
Y1093188D03*
Y1101062D03*
Y1108936D03*
Y1116810D03*
Y1124684D03*
Y1132558D03*
Y1140432D03*
Y1148306D03*
Y1156180D03*
Y1164055D03*
Y1171929D03*
Y1179803D03*
Y1187677D03*
Y1195551D03*
Y1203425D03*
Y1211299D03*
Y1219173D03*
Y1227047D03*
Y1234921D03*
Y1242795D03*
Y1250669D03*
Y1258543D03*
Y1266417D03*
Y1274291D03*
Y1282165D03*
Y1290039D03*
Y1297913D03*
Y1305787D03*
Y1313661D03*
Y1321535D03*
Y1329409D03*
Y1337283D03*
Y1353031D03*
Y1360905D03*
Y1368779D03*
Y1376653D03*
Y1384527D03*
G54D25*
X65354Y101180D03*
X55511Y105117D03*
X51574Y114960D03*
X55511Y124803D03*
X65354Y128740D03*
Y451180D03*
X55511Y455117D03*
X51574Y464960D03*
X55511Y474803D03*
X65354Y478740D03*
Y801180D03*
X55511Y805117D03*
X51574Y814960D03*
X55511Y824803D03*
X65354Y828740D03*
Y1151180D03*
X55511Y1155117D03*
X51574Y1164960D03*
X55511Y1174803D03*
X65354Y1178740D03*
Y1501180D03*
X55511Y1505117D03*
X51574Y1514960D03*
X55511Y1524803D03*
X65354Y1528740D03*
Y1851180D03*
X55511Y1855117D03*
X51574Y1864960D03*
X55511Y1874803D03*
X65354Y1878740D03*
X75197Y105117D03*
Y124803D03*
X79134Y114960D03*
Y464960D03*
X75197Y455117D03*
Y474803D03*
Y805117D03*
Y824803D03*
X79134Y814960D03*
Y1164960D03*
X75197Y1155117D03*
Y1174803D03*
Y1505117D03*
Y1524803D03*
X79134Y1514960D03*
Y1864960D03*
X75197Y1855117D03*
Y1874803D03*
X307086Y113385D03*
X297243Y117322D03*
X293306Y127165D03*
X297243Y137008D03*
X307086Y140945D03*
Y463385D03*
X297243Y467322D03*
X293306Y477165D03*
X297243Y487008D03*
X307086Y490945D03*
Y813385D03*
X297243Y817322D03*
X293306Y827165D03*
X297243Y837008D03*
X307086Y840945D03*
Y1329724D03*
X297243Y1333661D03*
X293306Y1343504D03*
X297243Y1353347D03*
X307086Y1357284D03*
Y1679724D03*
X297243Y1683661D03*
X293306Y1693504D03*
X297243Y1703347D03*
X307086Y1707284D03*
X307087Y2029723D03*
X297244Y2033660D03*
X293307Y2043503D03*
X297244Y2053346D03*
X307087Y2057283D03*
X320866Y127165D03*
X316929Y117322D03*
Y137008D03*
Y467322D03*
Y487008D03*
X320866Y477165D03*
Y827165D03*
X316929Y817322D03*
Y837008D03*
Y1333661D03*
Y1353347D03*
X320866Y1343504D03*
Y1693504D03*
X316929Y1683661D03*
Y1703347D03*
X316930Y2033660D03*
Y2053346D03*
X320867Y2043503D03*
G54D26*
X65354Y114960D03*
Y464960D03*
Y814960D03*
Y1164960D03*
Y1514960D03*
Y1864960D03*
X307086Y127165D03*
Y477165D03*
Y827165D03*
Y1343504D03*
Y1693504D03*
X307087Y2043503D03*
G54D35*
X307086Y1883071D03*
G54D17*
X20468Y696341D03*
Y984333D03*
X20472Y1054606D03*
Y1342598D03*
G54D36*
X359842Y78780D03*
Y253780D03*
Y428779D03*
Y603779D03*
Y778780D03*
Y953780D03*
Y1128779D03*
Y1303780D03*
Y1478780D03*
Y1653780D03*
Y1828779D03*
Y2003780D03*
G54D27*
X55254Y554500D03*
Y1612504D03*
G54D18*
X25389Y1030199D03*
X25393Y1388464D03*
G54D37*
X359677Y306891D03*
X362236D03*
Y329891D03*
X359677D03*
X354000Y656986D03*
X356559D03*
X359118D03*
X361677D03*
Y679986D03*
X359118D03*
X356559D03*
X354000D03*
X351983Y1882006D03*
X354542D03*
X357101D03*
X359660D03*
X362219D03*
Y1905006D03*
X359660D03*
X357101D03*
X354542D03*
X351983D03*
X364795Y306891D03*
X367354D03*
X369913D03*
X372472D03*
X375031D03*
Y329891D03*
X372472D03*
X369913D03*
X367354D03*
X364795D03*
X364236Y656986D03*
X366795D03*
X369354D03*
Y679986D03*
X366795D03*
X364236D03*
X372122Y1347255D03*
X374681D03*
X377240D03*
X379799D03*
X382358D03*
X384917D03*
X387476D03*
Y1370255D03*
X384917D03*
X382358D03*
X379799D03*
X377240D03*
X374681D03*
X372122D03*
X364778Y1882006D03*
X367337D03*
Y1905006D03*
X364778D03*
G54D19*
X23402Y1668874D03*
Y1685410D03*
Y1701945D03*
Y1718480D03*
Y1735016D03*
Y1751551D03*
Y1768087D03*
Y1784622D03*
Y1817693D03*
Y1801158D03*
X45056Y1668874D03*
Y1685410D03*
Y1701945D03*
Y1718480D03*
Y1735016D03*
Y1751551D03*
Y1768087D03*
Y1784622D03*
Y1801158D03*
G54D28*
X55158Y882277D03*
X344826Y2035270D03*
X389572Y66182D03*
G54D38*
X385146Y333689D03*
Y330539D03*
X380915Y333668D03*
Y330518D03*
G54D29*
X119920Y18071D03*
Y28071D03*
Y38071D03*
Y48071D03*
Y58071D03*
Y68071D03*
Y78071D03*
Y88071D03*
Y98071D03*
Y108071D03*
Y118071D03*
Y128071D03*
Y138071D03*
Y148071D03*
Y158071D03*
Y168071D03*
Y178071D03*
Y188071D03*
Y198071D03*
Y208071D03*
Y218071D03*
Y228071D03*
Y238071D03*
Y248071D03*
Y258071D03*
Y268071D03*
Y278071D03*
Y288071D03*
Y298071D03*
Y308071D03*
Y318071D03*
Y366102D03*
Y376102D03*
Y386102D03*
Y396102D03*
Y406102D03*
Y416102D03*
Y426102D03*
Y436102D03*
Y446102D03*
Y456102D03*
Y466102D03*
Y476102D03*
Y486102D03*
Y496102D03*
Y506102D03*
Y516102D03*
Y526102D03*
Y536102D03*
Y546102D03*
Y556102D03*
Y566102D03*
Y576102D03*
Y586102D03*
Y596102D03*
Y606102D03*
Y616102D03*
Y626102D03*
Y636102D03*
Y646102D03*
Y656102D03*
Y666102D03*
Y714134D03*
Y724134D03*
Y734134D03*
Y744134D03*
Y754134D03*
Y764134D03*
Y774134D03*
Y784134D03*
Y794134D03*
Y804134D03*
Y814134D03*
Y824134D03*
Y834134D03*
Y844134D03*
Y854134D03*
Y864134D03*
Y874134D03*
Y884134D03*
Y894134D03*
Y904134D03*
Y914134D03*
Y924134D03*
Y934134D03*
Y944134D03*
Y954134D03*
Y964134D03*
Y974134D03*
Y984134D03*
Y994134D03*
Y1004134D03*
Y1014134D03*
Y1062165D03*
Y1072165D03*
Y1082165D03*
Y1092165D03*
Y1102165D03*
Y1112165D03*
Y1122165D03*
Y1132165D03*
Y1142165D03*
Y1152165D03*
Y1162165D03*
Y1172165D03*
Y1182165D03*
Y1192165D03*
Y1202165D03*
Y1212165D03*
Y1222165D03*
Y1232165D03*
Y1242165D03*
Y1252165D03*
Y1262165D03*
Y1272165D03*
Y1282165D03*
Y1292165D03*
Y1302165D03*
Y1312165D03*
Y1322165D03*
Y1332165D03*
Y1342165D03*
Y1352165D03*
Y1362165D03*
Y1410197D03*
Y1420197D03*
Y1430197D03*
Y1440197D03*
Y1450197D03*
Y1460197D03*
Y1470197D03*
Y1480197D03*
Y1490197D03*
Y1500197D03*
Y1510197D03*
Y1520197D03*
Y1530197D03*
Y1540197D03*
Y1550197D03*
Y1560197D03*
Y1570197D03*
Y1580197D03*
Y1590197D03*
Y1600197D03*
Y1610197D03*
Y1620197D03*
Y1630197D03*
Y1640197D03*
Y1650197D03*
Y1660197D03*
Y1670197D03*
Y1680197D03*
Y1690197D03*
Y1700197D03*
Y1710197D03*
Y1758228D03*
Y1768228D03*
Y1778228D03*
Y1788228D03*
Y1798228D03*
Y1808228D03*
Y1818228D03*
Y1828228D03*
Y1838228D03*
Y1848228D03*
Y1858228D03*
Y1868228D03*
Y1878228D03*
Y1888228D03*
Y1898228D03*
Y1908228D03*
Y1918228D03*
Y1928228D03*
Y1938228D03*
Y1948228D03*
Y1958228D03*
Y1968228D03*
Y1978228D03*
Y1988228D03*
Y1998228D03*
Y2008228D03*
Y2018228D03*
Y2028228D03*
Y2038228D03*
Y2048228D03*
Y2058228D03*
X139920Y28071D03*
Y18071D03*
Y58071D03*
Y48071D03*
Y38071D03*
Y78071D03*
Y68071D03*
Y98071D03*
Y88071D03*
Y128071D03*
Y118071D03*
Y108071D03*
Y148071D03*
Y138071D03*
Y178071D03*
Y168071D03*
Y158071D03*
Y198071D03*
Y188071D03*
Y228071D03*
Y218071D03*
Y208071D03*
Y248071D03*
Y238071D03*
Y268071D03*
Y258071D03*
Y298071D03*
Y288071D03*
Y278071D03*
Y318071D03*
Y308071D03*
Y328071D03*
Y366102D03*
Y396102D03*
Y386102D03*
Y376102D03*
Y416102D03*
Y406102D03*
Y436102D03*
Y426102D03*
Y466102D03*
Y456102D03*
Y446102D03*
Y486102D03*
Y476102D03*
Y516102D03*
Y506102D03*
Y496102D03*
Y536102D03*
Y526102D03*
Y566102D03*
Y556102D03*
Y546102D03*
Y586102D03*
Y576102D03*
Y606102D03*
Y596102D03*
Y636102D03*
Y626102D03*
Y616102D03*
Y656102D03*
Y646102D03*
Y676102D03*
Y666102D03*
Y734134D03*
Y724134D03*
Y714134D03*
Y754134D03*
Y744134D03*
Y774134D03*
Y764134D03*
Y804134D03*
Y794134D03*
Y784134D03*
Y824134D03*
Y814134D03*
Y854134D03*
Y844134D03*
Y834134D03*
Y874134D03*
Y864134D03*
Y904134D03*
Y894134D03*
Y884134D03*
Y924134D03*
Y914134D03*
Y944134D03*
Y934134D03*
Y974134D03*
Y964134D03*
Y954134D03*
Y994134D03*
Y984134D03*
Y1024134D03*
Y1014134D03*
Y1004134D03*
Y1072165D03*
Y1062165D03*
Y1092165D03*
Y1082165D03*
Y1122165D03*
Y1112165D03*
Y1102165D03*
Y1142165D03*
Y1132165D03*
Y1162165D03*
Y1152165D03*
Y1192165D03*
Y1182165D03*
Y1172165D03*
Y1212165D03*
Y1202165D03*
Y1242165D03*
Y1232165D03*
Y1222165D03*
Y1262165D03*
Y1252165D03*
Y1282165D03*
Y1272165D03*
Y1312165D03*
Y1302165D03*
Y1292165D03*
Y1332165D03*
Y1322165D03*
Y1362165D03*
Y1352165D03*
Y1342165D03*
Y1372165D03*
Y1410197D03*
Y1430197D03*
Y1420197D03*
Y1460197D03*
Y1450197D03*
Y1440197D03*
Y1480197D03*
Y1470197D03*
Y1500197D03*
Y1490197D03*
Y1530197D03*
Y1520197D03*
Y1510197D03*
Y1550197D03*
Y1540197D03*
Y1580197D03*
Y1570197D03*
Y1560197D03*
Y1600197D03*
Y1590197D03*
Y1620197D03*
Y1610197D03*
Y1650197D03*
Y1640197D03*
Y1630197D03*
Y1670197D03*
Y1660197D03*
Y1700197D03*
Y1690197D03*
Y1680197D03*
Y1720197D03*
Y1710197D03*
Y1768228D03*
Y1758228D03*
Y1798228D03*
Y1788228D03*
Y1778228D03*
Y1818228D03*
Y1808228D03*
Y1838228D03*
Y1828228D03*
Y1868228D03*
Y1858228D03*
Y1848228D03*
Y1888228D03*
Y1878228D03*
Y1918228D03*
Y1908228D03*
Y1898228D03*
Y1938228D03*
Y1928228D03*
Y1958228D03*
Y1948228D03*
Y1988228D03*
Y1978228D03*
Y1968228D03*
Y2008228D03*
Y1998228D03*
Y2038228D03*
Y2028228D03*
Y2018228D03*
Y2058228D03*
Y2048228D03*
Y2068228D03*
G54D39*
X379000Y672905D03*
X375850D03*
X384867Y1377774D03*
X388017D03*
X381927Y1901748D03*
X378777D03*
M02*
